# Barreleye-G2_Tri-mode Expander-DVT-X01-SKU-BOM-X07-20171222_Final.xls.xlsx — SKU3 (bom)
| FOXCONN TECHNOLOGY GROUP |  |  |  |  |  |  |  |  |  |  |  |  |  |  |  |  |  |  |  |
| BILL OF MATERIAL |  |  |  |  |  |  |  |  |  |  |  |  |  |  |  |  |  |  |  |
| REV OF  BOM |  | CUSTOMER |  | <name> |  | CUSTOMER P/N |  | AA P/N：1A42NC400-600-3 | PWA DESCRIPTION |  |  |  | PRODUCT CODE |  |  | PWA  REV |  | DATE |  |
| Sourcing (Single/Sole/Multi) | Critical Commodity (Y or N) | Component Class (1, 2, other) | Customer PSL (Y or N) | Line Item | Item Number | Foxconn P/N | Customer P/N | Part Description | Manufacturer  Full Name | Manufacturer  Part Number | Qty | RoHS Status | Location | CC Qual Build: | Qual by (Customer / ODM ?) | The Date of Change Part or Add 2nd Source | Configuration Identifier | Customer Comments | ODM Comments |
|  |  |  |  | 1 | 1 | 0101FGB00-000-G |  | PCB,Zaius-Tri-mode Expander DVT-X01,Blu,10L,9.134*5.118,G | GOLD CIRCUIT ELECTRONICS LTD. | 0101FGB00-000-G | 1 | G | PCB |  |  |  |  |  |  |
|  |  |  |  |  | 1 | 0101FGB00-000-G |  | PCB,Zaius-Tri-mode Expander DVT-X01,Blu,10L,9.134*5.118,G | ZHUHAI FOUNDER PRINTED CIRCUIT BOARD（HK） DEVELOPMENT LIMITED | 0101FGB00-000-G |  | G |  |  |  |  |  |  |  |
|  |  |  |  | 2 | 2 | 62111H200-018-G |  | ECAP,680uF,+/-20%,16V,105_x0003_,G,SMD10X10.5,ESR<=80mOhm | RUBYCON CORP. | 16TZV680M10X10.5 | 2 | G | CE1,CE2 |  |  |  |  |  |  |
|  |  |  |  | 3 | 3 | 620101T02-015-G | - | CAP,100nF,+/-10%,X7R,16V,G,SMD0402 | MURATA ELEC. NORTH AMERICA | GRM155R71C104K | 35 | G | PSCC1,C1,PFCC2,PELC2,PLTC5,C8,PSRC10,PLTC11,PELC11,PFCC13,PECC15,PECC16,PECC18,PECC19,C223,C225,C226,C229,C231,C393,C394,C395,C396,C397,C411,C413,C610,C611,C612,C968,C970,C1524,C2004,C2180,C2183 |  |  |  |  |  |  |
|  |  |  |  |  | 3 | 620101T00-012-G |  | CAP,100nF,+/-10%,X7R,16V,G,SMD0402 | WALSIN TECHNOLOGY CORPORATION | 0402B104K160CT |  | G |  |  |  |  |  |  |  |
|  |  |  |  |  | 3 | 620101T00-026-G |  | CAP,100nF,+/-10%,X7R,16V,G,SMD0402 | SAMSUNG SEMICONDUCTOR | CL05B104KO5NNNC |  | G |  |  |  |  |  |  |  |
|  |  |  |  |  | 3 | 620101T00-015-G |  | CAP,100nF,+/-10%,X7R,16V,G,SMD0402 | MURATA ELEC. NORTH AMERICA | GRM155R71C104KA88D |  | G |  |  |  |  |  |  |  |
|  |  |  |  | 4 | 4 | 62010BN00-015-G | - | CAP,1uF,+/-10%,X5R,6.3V,G,SMD0402 | MURATA ELEC. NORTH AMERICA | GRM155R60J105K | 3 | G | C2,C4,C5 |  |  |  |  |  |  |
|  |  |  |  |  | 4 | 62010BN00-011-G |  | CAP,1uF,+/-10%,X5R,6.3V,G,SMD0402 | YAGEO CORPORATION COMPONENT | CC0402KRX5R5BB105 |  | G |  |  |  |  |  |  |  |
|  |  |  |  |  | 4 | 62010BN00-012-G |  | CAP,1uF,+/-10%,X5R,6.3V,G,SMD0402 | WALSIN TECHNOLOGY CORPORATION | 0402X105K6R3CT |  | G |  |  |  |  |  |  |  |
|  |  |  |  |  | 4 | 62010BN00-026-G |  | CAP,1uF,+/-10%,X5R,6.3V,G,SMD0402 | SAMSUNG SEMICONDUCTOR | CL05A105KQ5NNNC |  | G |  |  |  |  |  |  |  |
|  |  |  |  |  | 4 | 62010BN00-023-G |  | CAP,1uF,+/-10%,X5R,6.3V,G,SMD0402 | TAIYO ELECTRIC IND.CO.LTD | JMK105BJ105KV |  | G |  |  |  |  |  |  |  |
|  |  |  |  | 5 | 5 | 620106200-015-G | - | CAP,10nF,+/-10%,X7R,16V,G,SMD0402 | MURATA ELEC. NORTH AMERICA | GRM155R71C103K | 33 | G | C3,C6,C7,C25,C30,C39,C44,C49,C54,C61,C62,C69,C70,C77,C78,C85,C86,C93,C94,C101,C102,C109,C110,C117,C118,C125,C126,C133,C134,C141,C142,C149,C150 |  |  |  |  |  |  |
|  |  |  |  |  | 5 | 620106200-012-G |  | CAP,10nF,+/-10%,X7R,16V,G,SMD0402 | WALSIN TECHNOLOGY CORPORATION | 0402B103K160CT |  | G |  |  |  |  |  |  |  |
|  |  |  |  |  | 5 | 620106200-026-G |  | CAP,10nF,+/-10%,X7R,16V,G,SMD0402 | SAMSUNG SEMICONDUCTOR | CL05B103KO5NNNC |  | G |  |  |  |  |  |  |  |
|  |  |  |  |  | 5 | 620106200-023-G |  | CAP,10nF,+/-10%,X7R,16V,G,SMD0402 | TAIYO ELECTRIC IND.CO.LTD | EMK105B7103KV-F |  | G |  |  |  |  |  |  |  |
|  |  |  |  | 6 | 6 | 620108H00-015-G | - | CAP,22uF,+/-20%,X5R,6.3V,G,SMD0805 | MURATA ELEC. NORTH AMERICA | GRM21BR60J226M | 10 | G | C9,C13,C17,C21,C26,C31,C35,C40,C45,C50 |  |  |  |  |  |  |
|  |  |  |  |  | 6 | 620108H04-023-G |  | CAP,22uF,+/-20%,X5R,6.3V,G,SMD0805 | TAIYO ELECTRIC IND.CO.LTD | JMK212BJ226MG-T |  | G |  |  |  |  |  |  |  |
|  |  |  |  |  | 6 | 620108H00-026-G |  | CAP,22uF,+/-20%,X5R,6.3V,G,SMD0805 | SAMSUNG SEMICONDUCTOR | CL21A226MQQNNNE |  | G |  |  |  |  |  |  |  |
|  |  |  |  |  | 6 | 620108H00-011-G |  | CAP,22uF,+/-20%,X5R,6.3V,G,SMD0805 | YAGEO CORPORATION COMPONENT | CC0805MKX5R5BB226 |  | G |  |  |  |  |  |  |  |
|  |  |  |  | 7 | 7 | 62010L000-015-G | - | CAP,10uF,+/-20%,X5R,6.3V,G,SMD0603 | MURATA ELEC. NORTH AMERICA | GRM188R60J106M | 23 | G | C10,C14,C18,C22,C27,C32,C36,C41,C46,C51,C151,C152,C153,C154,C155,C191,C192,C193,C194,C224,C227,C228,C230 |  |  |  |  |  |  |
|  |  |  |  |  | 7 | 62010L000-023-G |  | CAP,10uF,+/-20%,X5R,6.3V,G,SMD0603 | TAIYO ELECTRIC IND.CO.LTD | JMK107BJ106MA-T |  | G |  |  |  |  |  |  |  |
|  |  |  |  |  | 7 | 62010L000-012-G |  | CAP,10uF,+/-20%,X5R,6.3V,G,SMD0603 | WALSIN TECHNOLOGY CORPORATION | 0603X106M6R3CT |  | G |  |  |  |  |  |  |  |
|  |  |  |  |  | 7 | 62010L000-026-G |  | CAP,10uF,+/-20%,X5R,6.3V,G,SMD0603 | SAMSUNG SEMICONDUCTOR | CL10A106MQ8NNNC |  | G |  |  |  |  |  |  |  |
|  |  |  |  |  | 7 | 62010L000-011-G |  | CAP,10uF,+/-20%,X5R,6.3V,G,SMD0603 | YAGEO CORPORATION COMPONENT | CC0603MRX5R5BB106 |  | G |  |  |  |  |  |  |  |
|  |  |  |  | 8 | 8 | 62012NU00-015-G | - | CAP,1uF,+/-10%,X7R,6.3V,G,SMD0402 | MURATA ELEC. NORTH AMERICA | GRM155R70J105KA12D | 22 | G | C11,C15,C19,C23,C28,C33,C37,C42,C47,C52,C57,C65,C73,C81,C89,C97,C105,C113,C121,C129,C137,C145 |  |  |  |  |  |  |
|  |  |  |  |  | 8 | 62012NU00-026-G |  | CAP,1uF,+/-10%,X7R,6.3V,G,SMD0402 | SAMSUNG SEMICONDUCTOR | CL05B105KQ5NQNC |  | G |  |  |  |  |  |  |  |
|  |  |  |  | 9 | 9 | 620103700-015-G | - | CAP,100nF,+/-10%,X7R,10V,G,SMD0402 | MURATA ELEC. NORTH AMERICA | GRM155R71A104K | 106 | G | PSLC10,PSGC10,C12,C16,C20,C24,C29,C34,C38,C43,C48,C53,C58,C59,C60,C66,C67,C68,C74,C75,C76,C82,C83,C84,C90,C91,C92,C98,C99,C100,C106,C107,C108,C114,C115,C116,C122,C123,C124,C130,C131,C132,C138,C139,C140,C146,C147,C148,C161,C162,C163,C164,C165,C166,C167,C168,C169,C170,C171,C172,C173,C174,C175,C176,C177,C178,C179,C180,C181,C182,C183,C184,C185,C186,C187,C188,C189,C190,C199,C200,C201,C202,C203,C204,C205,C206,C207,C208,C209,C210,C211,C212,C213,C214,C215,C216,C217,C218,C219,C220,C221,C222,C415,C2179,C2181,C2182 |  |  |  |  |  |  |
|  |  |  |  |  | 9 | 620103700-012-G |  | CAP,0.1uF,+/-10%,X7R,10V,G,SMD0402 | WALSIN TECHNOLOGY CORPORATION | 0402B104K100CT |  | G |  |  |  |  |  |  |  |
|  |  |  |  |  | 9 | 620103700-023-G |  | CAP,100nF,+/-10%,X7R,10V,G,SMD0402 | TAIYO ELECTRIC IND.CO.LTD | LMK105B7104KV-F |  | G |  |  |  |  |  |  |  |
|  |  |  |  |  | 9 | 620103700-026-G |  | CAP,100nF,+/-10%,X7R,10V,G,SMD0402 | SAMSUNG SEMICONDUCTOR | CL05B104KP5NNNC |  | G |  |  |  |  |  |  |  |
|  |  |  |  | 10 | 10 | 620132700-015-G |  | CAP,100uF,+/-20%,X5R,6.3V,G,SMD0805 | MURATA ELEC. NORTH AMERICA | GRM21BR60J107ME15L | 12 | G | C55,C63,C71,C79,C87,C95,C103,C111,C119,C127,C135,C143 |  |  |  |  |  |  |
|  |  |  |  |  | 10 | 620132700-012-G |  | CAP,100uF,+/-20%,X5R,6.3V,G,SMD0805 | WALSIN TECHNOLOGY CORPORATION | 0805X107M6R3CT |  | G |  |  |  |  |  |  |  |
|  |  |  |  | 11 | 11 | 62012Y400-015-G |  | CAP,22uF,+/-20%,X5R,6.3V,G,SMD0402 | MURATA ELEC. NORTH AMERICA | GRM155R60J226ME11D | 12 | G | C56,C64,C72,C80,C88,C96,C104,C112,C120,C128,C136,C144 |  |  |  |  |  |  |
|  |  |  |  |  | 11 | 62012Y400-026-G |  | CAP,22uF,+/-20%,X5R,6.3V,G,SMD0402 | SAMSUNG SEMICONDUCTOR | CL05A226MQ5N6J8 |  | G |  |  |  |  |  |  |  |
|  |  |  |  |  | 11 | 62012Y400-011-G |  | CAP,22uF,+/-20%,X5R,6.3V,G,SMD0402 | YAGEO CORPORATION COMPONENT | CC0402MRX5R5BB226 |  | G |  |  |  |  |  |  |  |
|  |  |  |  |  | 11 | 62012Y400-012-G |  | CAP,22uF,+/-20%,X5R,6.3V,G,SMD0402 | WALSIN TECHNOLOGY CORPORATION | 0402X226M6R3CT |  | G |  |  |  |  |  |  |  |
|  |  |  |  | 12 | 12 | 62010P501-015-G | - | CAP,1nF,+/-10%,X7R,16V,G,SMD0402 | MURATA ELEC. NORTH AMERICA | GRM155R71C102KA01D | 9 | G | C156,C157,C158,C159,C160,C195,C196,C197,C198 |  |  |  |  |  |  |
|  |  |  |  |  | 12 | 62010P500-023-G |  | CAP,1nF,+/-10%,X7R,16V,G,SMD0402 | TAIYO ELECTRIC IND.CO.LTD | EMK105B7102KV-F |  | G |  |  |  |  |  |  |  |
|  |  |  |  |  | 12 | 62010P500-026-G |  | CAP,1nF,+/-10%,X7R,16V,G,SMD0402 | SAMSUNG SEMICONDUCTOR | CL05B102KO5NNNC |  | G |  |  |  |  |  |  |  |
|  |  |  |  | 13 | 13 | 62012QF00-023-G |  | CAP,10nF,+/-10%,X7R,16V,G,SMD0201 | TAIYO ELECTRIC IND.CO.LTD | EMK063B7103KP-F | 212 | G | C233,C234,C235,C236,C237,C238,C239,C240,C241,C242,C243,C244,C245,C246,C247,C248,C249,C250,C251,C252,C253,C254,C255,C256,C257,C258,C259,C260,C261,C262,C263,C264,C297,C298,C299,C300,C301,C302,C303,C304,C305,C306,C307,C308,C309,C310,C311,C312,C313,C314,C315,C316,C317,C318,C319,C320,C321,C322,C323,C324,C325,C326,C327,C328,C329,C330,C331,C332,C333,C334,C335,C336,C337,C338,C339,C340,C341,C342,C343,C344,C345,C346,C347,C348,C349,C350,C351,C352,C353,C354,C355,C356,C357,C358,C359,C360,C361,C362,C363,C364,C365,C366,C367,C368,C369,C370,C371,C372,C373,C374,C375,C376,C377,C378,C379,C380,C381,C382,C383,C384,C385,C386,C387,C388,C389,C390,C391,C392,C640,C641,C642,C643,C644,C645,C646,C647,C648,C649,C650,C651,C652,C653,C654,C655,C656,C657,C658,C659,C660,C661,C662,C663,C664,C665,C674,C675,C676,C677,C678,C679,C680,C681,C682,C725,C726,C727,C728,C729,C730,C731,C732,C733,C734,C735,C736,C737,C738,C739,C740,C741,C742,C743,C744,C745,C746,C747,C748,C749,C750,C751,C752,C753,C754,C755,C756,C757,C758,C759,C775,C776,C777,C778,C779,C780,C781,C797,C798,C799,C800,C801,C802,C803 |  |  |  |  |  |  |
|  |  |  |  |  | 13 | 62012QF00-012-G |  | CAP,10nF,+/-10%,X7R,16V,G,SMD0201 | WALSIN TECHNOLOGY CORPORATION | 0201B103K160CT |  | G |  |  |  |  |  |  |  |
|  |  |  |  |  | 13 | 62012QF00-026-G |  | CAP,10nF,+/-10%,X7R,16V,G,SMD0201 | SAMSUNG SEMICONDUCTOR | CL03B103KO3NNNC |  | G |  |  |  |  |  |  |  |
|  |  |  |  | 14 | 14 | 62012GG00-015-G | - | CAP,10uF,+/-10%,X7S,25V,G,SMD0805 | MURATA ELEC. NORTH AMERICA | GRM21BC71E106K | 7 | G | PLTC1,PSRC3,PSLC3,PSGC3,C398,C399,PSCC3004 |  |  |  |  |  |  |
|  |  |  |  |  | 14 | 62012GG00-012-G |  | CAP,10uF,+/-10%,X7S,25V,G,SMD0805 | WALSIN TECHNOLOGY CORPORATION | 0805A106K250CT |  | G |  |  |  |  |  |  |  |
|  |  |  |  | 15 | 15 | 62012A400-015-G | - | CAP,100nF,+/-10%,X7R,25V,G,SMD0402 | MURATA ELEC. NORTH AMERICA | GRM155R71E104KE14D | 17 | G | PSRC1,PSLC1,PSGC1,PELC3,PLTC4,PFCC4,PELC4,PSRC6,PSLC6,PSGC6,PELC10,PFCC11,PECC13,C400,C404,PSCC3002,PSCC3008 |  |  |  |  |  |  |
|  |  |  |  |  | 15 | 62012A400-023-G |  | CAP,100nF,+/-10%,X7R,25V,G,SMD0402 | TAIYO ELECTRIC IND.CO.LTD | TMK105B7104KV-FR |  | G |  |  |  |  |  |  |  |
|  |  |  |  |  | 15 | 62012A400-026-G |  | CAP,100nF,+/-10%,X7R,25V,G,SMD0402 | SAMSUNG SEMICONDUCTOR | CL05B104KA5NNNC |  | G |  |  |  |  |  |  |  |
|  |  |  |  |  | 15 | 62012A400-012-G |  | CAP,100nF,+/-10%,X7R,25V,G,SMD0402 | WALSIN TECHNOLOGY CORPORATION | 0402B104K250CT |  | G |  |  |  |  |  |  |  |
|  |  |  |  | 16 | 16 | 620109N00-015-G |  | CAP,2.2uF,+/-10%,X7R,10V,G,SMD0603 | MURATA ELEC. NORTH AMERICA | GRM188R71A225K | 1 | G | C401 |  |  |  |  |  |  |
|  |  |  |  |  | 16 | 620109N00-023-G |  | CAP,2.2uF,+/-10%,X7R,10V,G,SMD0603 | TAIYO ELECTRIC IND.CO.LTD | LMK107B7225KA-T |  | G |  |  |  |  |  |  |  |
|  |  |  |  |  | 16 | 620109N00-026-G |  | CAP,2.2uF,+/-10%,X7R,10V,G,SMD0603 | SAMSUNG SEMICONDUCTOR | CL10B225KP8NNNC |  | G |  |  |  |  |  |  |  |
|  |  |  |  | 17 | 17 | 62012H100-015-G | - | CAP,10uF,+/-20%,X6S,10V,G,SMD0603 | MURATA ELEC. NORTH AMERICA | GRM188C81A106M | 3 | G | PSRC16,C402,C403 |  |  |  |  |  |  |
|  |  |  |  |  | 17 | 62012H100-023-G |  | CAP,10uF,+/-20%,X6S,10V,G,SMD0603 | TAIYO ELECTRIC IND.CO.LTD | LMK107BC6106MA-T |  | G |  |  |  |  |  |  |  |
|  |  |  |  |  | 17 | 62012H100-026-G |  | CAP,10uF,+/-20%,X6S,10V,G,SMD0603 | SAMSUNG SEMICONDUCTOR | CL10X106MP8NRNC |  | G |  |  |  |  |  |  |  |
|  |  |  |  | 18 | 18 | 620108J00-015-G | - | CAP,100uF,+/-20%,X5R,6.3V,G,SMD1210 | MURATA ELEC. NORTH AMERICA | GRM32ER60J107M | 1 | G | C406 |  |  |  |  |  |  |
|  |  |  |  |  | 18 | 620108J00-012-G |  | CAP,100uF,+/-20%,X5R,6.3V,G,SMD1210 | WALSIN TECHNOLOGY CORPORATION | 1210X107M6R3CT |  | G |  |  |  |  |  |  |  |
|  |  |  |  |  | 18 | 620108J00-011-G |  | CAP,100uF,+/-20%,X5R,6.3V,G,SMD1210 | YAGEO CORPORATION COMPONENT | CC1210MKX5R5BB107 |  | G |  |  |  |  |  |  |  |
|  |  |  |  |  | 18 | 620108J00-026-G |  | CAP,100uF,+/-20%,X5R,6.3V,G,SMD1210 | SAMSUNG SEMICONDUCTOR | CL32A107MQVNNNE |  | G |  |  |  |  |  |  |  |
|  |  |  |  |  | 18 | 620108J07-023-G |  | CAP,100uF,+/-20%,X5R,6.3V,G,SMD1210 | TAIYO ELECTRIC IND.CO.LTD | JMK325ABJ107MM-T |  | G |  |  |  |  |  |  |  |
|  |  |  |  | 19 | 19 | 620100A00-015-G | - | CAP,10uF,+/-10%,X5R,16V,G,SMD1206 | MURATA ELEC. NORTH AMERICA | GRM31CR61C106K | 8 | G | C409,C410,C412,C414,C966,C967,C969,C971 |  |  |  |  |  |  |
|  |  |  |  |  | 19 | 620100A00-026-G |  | CAP,10uF,+/-10%,X5R,16V,G,SMD1206 | SAMSUNG SEMICONDUCTOR | CL31A106KOHNNNE |  | G |  |  |  |  |  |  |  |
|  |  |  |  |  | 19 | 620100A03-023-G |  | CAP,10uF,+/-10%,X5R,16V,G,SMD1206 | TAIYO ELECTRIC IND.CO.LTD | EMK316BJ106KL-T |  | G |  |  |  |  |  |  |  |
|  |  |  |  |  | 19 | 620100A00-012-G |  | CAP,10uF,+/-10%,X5R,16V,G,SMD1206 | WALSIN TECHNOLOGY CORPORATION | 1206X106K160CT |  | G |  |  |  |  |  |  |  |
|  |  |  |  |  | 19 | 620100A00-011-G |  | CAP,10uF,+/-10%,X5R,16V,G,SMD1206 | YAGEO CORPORATION COMPONENT | CC1206KKX5R7BB106 |  | G |  |  |  |  |  |  |  |
|  |  |  |  | 20 | 20 | 62011DF01-015-G | - | CAP,220nF,+/-10%,X7R,16V,G,SMD0402 | MURATA ELEC. NORTH AMERICA | GRM155R71C224K | 288 | G | C416,C417,C418,C419,C420,C421,C422,C423,C424,C425,C426,C427,C428,C429,C430,C431,C432,C433,C434,C435,C436,C437,C438,C439,C440,C441,C442,C443,C444,C445,C446,C447,C448,C449,C450,C451,C452,C453,C454,C455,C456,C457,C458,C459,C460,C461,C462,C463,C464,C465,C466,C467,C468,C469,C470,C471,C472,C473,C474,C475,C476,C477,C478,C479,C480,C481,C482,C485,C488,C489,C490,C491,C496,C497,C498,C499,C504,C505,C506,C507,C512,C513,C514,C515,C516,C517,C518,C519,C520,C521,C522,C523,C524,C525,C526,C527,C528,C529,C530,C531,C532,C533,C534,C535,C536,C537,C538,C539,C540,C541,C542,C543,C544,C545,C550,C551,C552,C553,C554,C555,C560,C561,C562,C563,C568,C569,C570,C571,C576,C577,C578,C582,C584,C585,C586,C587,C592,C593,C594,C595,C600,C601,C602,C603,C822,C823,C824,C825,C826,C827,C828,C829,C830,C831,C832,C833,C834,C835,C836,C837,C838,C839,C840,C841,C842,C843,C844,C845,C846,C847,C848,C849,C850,C851,C852,C853,C854,C855,C856,C857,C858,C859,C860,C862,C863,C864,C865,C866,C867,C868,C869,C870,C871,C872,C873,C874,C875,C876,C877,C878,C879,C880,C881,C882,C883,C884,C885,C886,C887,C888,C889,C890,C891,C892,C893,C894,C895,C896,C897,C898,C899,C900,C901,C910,C911,C912,C913,C914,C915,C916,C917,C918,C919,C920,C921,C922,C923,C924,C925,C926,C927,C928,C929,C930,C931,C932,C933,C934,C935,C936,C937,C938,C939,C940,C941,C942,C943,C944,C945,C946,C947,C948,C949,C950,C951,C952,C953,C954,C955,C956,C957,C958,C959,C960,C961,C962,C963,C964,C965,C2115,C2136,C2138,C2141,C2142,C2144,C2145,C2146,C2166 |  |  |  |  |  |  |
|  |  |  |  |  | 20 | 62011DF00-026-G |  | CAP,220nF,+/-10%,X7R,16V,G,SMD0402 | SAMSUNG SEMICONDUCTOR | CL05B224KO5NNNC |  | G |  |  |  |  |  |  |  |
|  |  |  |  |  | 20 | 62011DF00-023-G |  | CAP,220nF,+/-10%,X7R,16V,G,SMD0402 | TAIYO ELECTRIC IND.CO.LTD | EMK105B7224KV-FR |  | G |  |  |  |  |  |  |  |
|  |  |  |  | 21 | 21 | 620119R04-015-G | - | CAP,22uF,+/-20%,X6S,4V,G,SMD0805 | MURATA ELEC. NORTH AMERICA | GRM21BC80G226M | 35 | G | PSLC7,PSGC7,PSLC8,PSGC8,PSLC11,PSGC11,PSLC12,PSGC12,PFCC14,PSLC15,PSGC15,PFCC15,PFCC16,PFCC17,PFCC18,PFCC20,PFCC21,PFCC22,PFCC23,PFCC24,PFCC25,PFCC26,PFCC27,PFCC28,PFCC29,PECC29,PFCC30,PECC30,PFCC31,PFCC32,PFCC33,PFCC34,PECC40,PECC41,C609 |  |  |  |  |  |  |
|  |  |  |  |  | 21 | 620119R01-015-G |  | CAP,22uF,+/-20%,X6S,4V,G,SMD0805 | MURATA ELEC. NORTH AMERICA | GRM21BC80G226ME39K |  | G |  |  |  |  |  |  |  |
|  |  |  |  |  | 21 | 620119R00-023-G |  | CAP,22uF,+/-20%,X6S,4V,G,SMD0805 | TAIYO ELECTRIC IND.CO.LTD | AMK212C6226MG-T |  | G |  |  |  |  |  |  |  |
|  |  |  |  |  | 21 | 620119R00-026-G |  | CAP,22uF,+/-20%,X6S,4V,G,SMD0805 | SAMSUNG SEMICONDUCTOR | CL21X226MRQNNNE |  | G |  |  |  |  |  |  |  |
|  |  |  |  | 22 | 22 | 62012C800-015-G | - | CAP,100nF,+/-10%,X5R,16V,G,SMD0201 | MURATA ELEC. NORTH AMERICA | GRM033R61C104K | 82 | G | C614,C615,C616,C617,C618,C619,C620,C621,C622,C623,C624,C625,C626,C627,C628,C629,C630,C631,C632,C633,C634,C635,C636,C637,C638,C639,C666,C667,C668,C669,C670,C671,C672,C673,C691,C692,C693,C694,C695,C696,C697,C698,C699,C700,C701,C702,C703,C704,C705,C706,C707,C708,C709,C710,C711,C712,C713,C714,C715,C716,C717,C718,C719,C720,C721,C722,C723,C724,C768,C769,C770,C771,C772,C773,C774,C790,C791,C792,C793,C794,C795,C796 |  |  |  |  |  |  |
|  |  |  |  |  | 22 | 62012C800-023-G |  | CAP,100nF,+/-10%,X5R,16V,G,SMD0201 | TAIYO ELECTRIC IND.CO.LTD | EMK063BJ104KP-F |  | G |  |  |  |  |  |  |  |
|  |  |  |  |  | 22 | 62012C800-026-G |  | CAP,100nF,+/-10%,X5R,16V,G,SMD0201 | SAMSUNG SEMICONDUCTOR | CL03A104KO3NNNC |  | G |  |  |  |  |  |  |  |
|  |  |  |  |  | 22 | 62012C800-011-G |  | CAP,100nF,+/-10%,X5R,16V,G,SMD0201 | YAGEO CORPORATION COMPONENT | CC0201KRX5R7BB104 |  | G |  |  |  |  |  |  |  |
|  |  |  |  | 23 | 23 | 620105400-015-G |  | CAP,1uF,+/-10%,X7R,16V,G,SMD0603 | MURATA ELEC. NORTH AMERICA | GRM188R71C105K | 25 | G | PFCC12,C683,C684,C685,C686,C687,C688,C689,C690,C760,C761,C762,C763,C764,C765,C766,C767,C782,C783,C784,C785,C786,C787,C788,C789 |  |  |  |  |  |  |
|  |  |  |  |  | 23 | 620105400-012-G |  | CAP,1uF,+/-10%,X7R,16V,G,SMD0603 | WALSIN TECHNOLOGY CORPORATION | 0603B105K160CT |  | G |  |  |  |  |  |  |  |
|  |  |  |  |  | 23 | 620105400-011-G |  | CAP,1uF,+/-10%,X7R,16V,G,SMD0603 | YAGEO CORPORATION COMPONENT | CC0603KRX7R7BB105 |  | G |  |  |  |  |  |  |  |
|  |  |  |  |  | 23 | 620105400-026-G |  | CAP,1uF,+/-10%,X7R,16V,G,SMD0603 | SAMSUNG SEMICONDUCTOR | CL10B105KO8NNNC |  | G |  |  |  |  |  |  |  |
|  |  |  |  |  | 23 | 620105400-023-G |  | CAP,1uF,+/-10%,X7R,16V,G,SMD0603 | TAIYO ELECTRIC IND.CO.LTD | EMK107B7105KA-T |  | G |  |  |  |  |  |  |  |
|  |  |  |  | 24 | 24 | 620100L00-015-G | - | CAP,22pF,+/-5%,NPO(C0G),50V,G,SMD0402 | MURATA ELEC. NORTH AMERICA | GRM1555C1H220J | 2 | G | C806,C807 |  |  |  |  |  |  |
|  |  |  |  |  | 24 | 620100L08-012-G |  | CAP,22pF,+/-5%,NPO(C0G),50V,G,SMD0402 | WALSIN TECHNOLOGY CORPORATION | 0402N220J500CT |  | G |  |  |  |  |  |  |  |
|  |  |  |  |  | 24 | 620100L00-023-G |  | CAP,22pF,+/-5%,NPO(C0G),50V,G,SMD0402 | TAIYO ELECTRIC IND.CO.LTD | UMK105CG220JV-F |  | G |  |  |  |  |  |  |  |
|  |  |  |  |  | 24 | 620100L00-026-G |  | CAP,22pF,+/-5%,NPO(C0G),50V,G,SMD0402 | SAMSUNG SEMICONDUCTOR | CL05C220JB5NNNC |  | G |  |  |  |  |  |  |  |
|  |  |  |  | 25 | 25 | 620102U00-015-G | - | CAP,100nF,+/-10%,X5R,10V,G,SMD0402 | MURATA ELEC. NORTH AMERICA | GRM155R61A104K | 3 | G | C808,C2171,C2173 |  |  |  |  |  |  |
|  |  |  |  |  | 25 | 620102U00-023-G |  | CAP,100nF,+/-10%,X5R,10V,G,SMD0402 | TAIYO ELECTRIC IND.CO.LTD | LMK105BJ104KV-F |  | G |  |  |  |  |  |  |  |
|  |  |  |  |  | 25 | 620102U00-011-G |  | CAP,100nF,+/-10%,X5R,10V,G,SMD0402 | YAGEO CORPORATION COMPONENT | CC0402KRX5R6BB104 |  | G |  |  |  |  |  |  |  |
|  |  |  |  |  | 25 | 620102U00-026-G |  | CAP,100nF,+/-10%,X5R,10V,G,SMD0402 | SAMSUNG SEMICONDUCTOR | CL05A104KP5NNNC |  | G |  |  |  |  |  |  |  |
|  |  |  |  |  | 25 | 620102U00-012-G |  | CAP,100nF,+/-10%,X5R,10V,G,SMD0402 | WALSIN TECHNOLOGY CORPORATION | 0402X104K100CT |  | G |  |  |  |  |  |  |  |
|  |  |  |  | 26 | 26 | 62011CA01-015-G |  | CAP,10uF,+/-10%,X5R,10V,G,SMD0603 | MURATA ELEC. NORTH AMERICA | GRM188R61A106K | 1 | G | C2170 |  |  |  |  |  |  |
|  |  |  |  |  | 26 | 62011CA00-026-G |  | CAP,10uF,+/-10%,X5R,10V,G,SMD0603 | SAMSUNG SEMICONDUCTOR | CL10A106KP8NNNC |  | G |  |  |  |  |  |  |  |
|  |  |  |  |  | 26 | 62011CA00-011-G |  | CAP,10uF,+/-10%,X5R,10V,G,SMD0603 | YAGEO CORPORATION COMPONENT | CC0603KRX5R6BB106 |  | G |  |  |  |  |  |  |  |
|  |  |  |  |  | 26 | 62011CA00-012-G |  | CAP,10uF,+/-10%,X5R,10V,G,SMD0603 | WALSIN TECHNOLOGY CORPORATION | 0603X106K100CT |  | G |  |  |  |  |  |  |  |
|  |  |  |  | 27 | 27 | 62010JJ00-015-G | - | CAP,1uF,+/-10%,X5R,10V,G,SMD0402 | MURATA ELEC. NORTH AMERICA | GRM155R61A105K | 2 | G | PECC8,C2172 |  |  |  |  |  |  |
|  |  |  |  |  | 27 | 62010JJ01-023-G |  | CAP,1uF,+/-10%,X5R,10V,G,SMD0402 | TAIYO ELECTRIC IND.CO.LTD | LMK105BJ105KV-F |  | G |  |  |  |  |  |  |  |
|  |  |  |  |  | 27 | 62010JJ00-011-G |  | CAP,1uF,+/-10%,X5R,10V,G,SMD0402 | YAGEO CORPORATION COMPONENT | CC0402KRX5R6BB105 |  | G |  |  |  |  |  |  |  |
|  |  |  |  |  | 27 | 62010JJ00-012-G |  | CAP,1uF,+/-10%,X5R,10V,G,SMD0402 | WALSIN TECHNOLOGY CORPORATION | 0402X105K100CT |  | G |  |  |  |  |  |  |  |
|  |  |  |  |  | 27 | 62010JJ00-026-G |  | CAP,1uF,+/-10%,X5R,10V,G,SMD0402 | SAMSUNG SEMICONDUCTOR | CL05A105KP5NNNC |  | G |  |  |  |  |  |  |  |
|  |  |  |  | 28 | 28 | 520308900-214-G | - | DIODE,Schottky,BAR43FILM,30V,0.1A,G,SOT23-3,SMD | ST MICRO ELECTRONICS,INC | BAR43FILM | 7 | G | D1,D2,D3,D4,D5,D6,D7 |  |  |  |  |  |  |
|  |  |  |  | 29 | 29 | 521107T00-289-G | KX549 | LED,Gre,LTST-C190KGKT,2.4V,30mA,G,SMD0603 | LITE-ON TECHNOLOGY CORPORATION | LTST-C190KGKT | 29 | G | LED_HB1,LED_BLK1,LED_SASEXP_P0V9,LED_SW1_P0,LED_SW1_P1,LED_SW1_P2,LED_SW1_P3,LED_SW1_P4,LED_SW1_P5,LED_SW1_P6,LED_SW1_P7,LED_SW1_P8,LED_SW1_P9,LED_SW1_P10,LED_SW1_P11,LED_SW1_P12,LED_SW1_P13,LED_SW1_P14,LED_SW1_P15,LED_SW1_P16,LED_SW1_P17,LED_SW1_P18,LED_SW1_P19,LED_SW1_P20,LED_SW1_P21,LED_SW1_P22,LED_SW1_P23,LED_PEX9797_PG,LED_EXP_BP_PG |  |  |  |  |  |  |
|  |  |  |  | 30 | 30 | 720100W00-015-G |  | FB,330 Ohm@100MHz,+/-25%,1.5A,90mOhm,G,SMD0805 | MURATA ELEC. NORTH AMERICA | BLM21PG331SN1D | 1 | G | L1 |  |  |  |  |  |  |
|  |  |  |  | 31 | 31 | 720103500-174-G |  | FB,600 Ohm@100MHz,+/-25%,2A,100mOhm,G,SMD0805 | MAX ECHO TECHNOLOGIES CORP | ACMS201209A601 2A | 10 | G | L2,L3,L4,L5,L6,L7,L8,L9,L10,L11 |  |  |  |  |  |  |
|  |  |  |  | 32 | 32 | 72010A700-029-G |  | FB,30 Ohm@100MHz,+/-25%,6A,15mOhm,G,SMD0805 | VISHAY ENTER TECHNO LOGY.INC | ILHB0805ER300V | 12 | G | L12,L13,L14,L15,L16,L17,L18,L19,L20,L21,L22,L23 |  |  |  |  |  |  |
|  |  |  |  | 33 | 33 | 720101L00-074-G |  | FB,600Ohm@100MHz,+/-25%,200mA,500mOhm,SMD0603,G | CHILISIN ELECTRONICS CORP. | SBK160808T-601Y-N | 1 | G | L24 |  |  |  |  |  |  |
|  |  |  |  | 34 | 34 | 62120BA00-022-G |  | SPEA,CAP,180uF,+/-20%,16V,105C,G,SMD6.3*5.9,ESR<=22mOhm | SANYO ELECTRIC CO., LTD. | 16SVPF180M | 1 | G | PECCE1 |  |  |  |  |  |  |
|  |  |  |  | 35 | 35 | 62120ES00-024-G | - | SPEA CAP,560uF,+/-20%,2V,105C,G,SMD2816,ESR<=3mOhm | PANASONIC INDUSTRIAL CO.,LTD. | EEFGX0D561L | 4 | G | PECCE3,PECCE4,PECCE5,PECCE6 |  |  |  |  |  |  |
|  |  |  |  | 36 | 36 | 620103K00-015-G | - | CAP,1nF,+/-10%,X7R,50V,G,SMD0402 | MURATA ELEC. NORTH AMERICA | GRM155R71H102K | 3 | G | PECC1,PELC17,PFCC19 |  |  |  |  |  |  |
|  |  |  |  |  | 36 | 620103K00-012-G |  | CAP,1nF,+/-10%,X7R,50V,G,SMD0402 | WALSIN TECHNOLOGY CORPORATION | 0402B102K500CT |  | G |  |  |  |  |  |  |  |
|  |  |  |  |  | 36 | 620103K00-026-G |  | CAP,1nF,+/-10%,X7R,50V,G,SMD0402 | SAMSUNG SEMICONDUCTOR | CL05B102KB5NNNC |  | G |  |  |  |  |  |  |  |
|  |  |  |  |  | 36 | 620103K00-023-G |  | CAP,1nF,+/-10%,X7R,50V,G,SMD0402 | TAIYO ELECTRIC IND.CO.LTD | UMK105B7102KV-F |  | G |  |  |  |  |  |  |  |
|  |  |  |  | 37 | 37 | 62010FY00-015-G | - | CAP,1.5nF,+/-10%,X7R,50V,G,SMD0402 | MURATA ELEC. NORTH AMERICA | GRM155R71H152K | 1 | G | PECC2 |  |  |  |  |  |  |
|  |  |  |  |  | 37 | 62010FY00-012-G |  | CAP,1.5nF,+/-10%,X7R,50V,G,SMD0402 | WALSIN TECHNOLOGY CORPORATION | 0402B152K500CT |  | G |  |  |  |  |  |  |  |
|  |  |  |  |  | 37 | 62010FY00-026-G |  | CAP,1.5nF,+/-10%,X7R,50V,G,SMD0402 | SAMSUNG SEMICONDUCTOR | CL05B152KB5NNNC |  | G |  |  |  |  |  |  |  |
|  |  |  |  |  | 37 | 62010FY00-023-G |  | CAP,1.5nF,+/-10%,X7R,50V,G,SMD0402 | TAIYO ELECTRIC IND.CO.LTD | UMK105B7152KV-F |  | G |  |  |  |  |  |  |  |
|  |  |  |  | 38 | 38 | 620103U00-015-G | - | CAP,470pF,+/-10%,X7R,50V,G,SMD0402 | MURATA ELEC. NORTH AMERICA | GRM155R71H471K | 1 | G | PECC4 |  |  |  |  |  |  |
|  |  |  |  |  | 38 | 620103U00-012-G |  | CAP,470pF,+/-10%,X7R,50V,G,SMD0402 | WALSIN TECHNOLOGY CORPORATION | 0402B471K500CT |  | G |  |  |  |  |  |  |  |
|  |  |  |  |  | 38 | 620103U00-026-G |  | CAP,470pF,+/-10%,X7R,50V,G,SMD0402 | SAMSUNG SEMICONDUCTOR | CL05B471KB5NNNC |  | G |  |  |  |  |  |  |  |
|  |  |  |  |  | 38 | 620103U00-023-G |  | CAP,470pF,+/-10%,X7R,50V,G,SMD0402 | TAIYO ELECTRIC IND.CO.LTD | UMK105B7471KV-F |  | G |  |  |  |  |  |  |  |
|  |  |  |  | 39 | 39 | 620114T00-015-G | - | CAP,330nF,+/-10%,X5R,10V,G,SMD0402 | MURATA ELEC. NORTH AMERICA | GRM155R61A334K | 1 | G | PECC7 |  |  |  |  |  |  |
|  |  |  |  |  | 39 | 620114T00-012-G |  | CAP,330nF,+/-10%,X5R,10V,G,SMD0402 | WALSIN TECHNOLOGY CORPORATION | 0402X334K100CT |  | G |  |  |  |  |  |  |  |
|  |  |  |  |  | 39 | 620114T00-011-G |  | CAP,330nF,+/-10%,X5R,10V,G,SMD0402 | YAGEO CORPORATION COMPONENT | CC0402KRX5R6BB334 |  | G |  |  |  |  |  |  |  |
|  |  |  |  | 40 | 40 | 62012GE00-015-G | - | CAP,4.7uF,+/-20%,X7S,10V,G,SMD0603 | MURATA ELEC. NORTH AMERICA | GRM188C71A475M | 1 | G | PECC9 |  |  |  |  |  |  |
|  |  |  |  |  | 40 | 62012T800-023-G |  | CAP,4.7uF,+/-10%,X7S,10V,G,SMD0603 | TAIYO ELECTRIC IND.CO.LTD | LDK107BC7475KA-T |  | G |  |  |  |  |  |  |  |
|  |  |  |  | 41 | 41 | 62011F100-015-G |  | CAP,1uF,+/-10%,X7R,25V,G,SMD0603 | MURATA ELEC. NORTH AMERICA | GRM188R71E105K | 2 | G | PFCC3,PECC10 |  |  |  |  |  |  |
|  |  |  |  |  | 41 | 62011F100-023-G |  | CAP,1uF,+/-10%,X7R,25V,G,SMD0603 | TAIYO ELECTRIC IND.CO.LTD | TMK107B7105KA-T |  | G |  |  |  |  |  |  |  |
|  |  |  |  |  | 41 | 62011F100-026-G |  | CAP,1uF,+/-10%,X7R,25V,G,SMD0603 | SAMSUNG SEMICONDUCTOR | CL10B105KA8NNNC |  | G |  |  |  |  |  |  |  |
|  |  |  |  | 42 | 42 | 62010L800-015-G | - | CAP,1nF,+/-5%,NPO(C0G),50V,G,SMD0402 | MURATA ELEC. NORTH AMERICA | GRM1555C1H102J | 3 | G | PSCC5,PECC11,PECC12 |  |  |  |  |  |  |
|  |  |  |  |  | 42 | 62010L800-012-G |  | CAP,1nF,+/-5%,NPO(C0G),50V,G,SMD0402 | WALSIN TECHNOLOGY CORPORATION | 0402N102J500CT |  | G |  |  |  |  |  |  |  |
|  |  |  |  |  | 42 | 62010L800-026-G |  | CAP,1nF,+/-5%,NPO(C0G),50V,G,SMD0402 | SAMSUNG SEMICONDUCTOR | CL05C102JB5NNNC |  | G |  |  |  |  |  |  |  |
|  |  |  |  | 43 | 43 | 62012P100-015-G |  | CAP,2.2uF,+/-20%,X7S,10V,G,SMD0402 | MURATA ELEC. NORTH AMERICA | GRM155C71A225M | 5 | G | PSRC5,PSLC5,PSGC5,PECC14,PECC17 |  |  |  |  |  |  |
|  |  |  |  |  | 43 | 62012P100-012-G |  | CAP,2.2uF,+/-20%,X7S,10V,G,SMD0402 | WALSIN TECHNOLOGY CORPORATION | 0402A225M100CT |  | G |  |  |  |  |  |  |  |
|  |  |  |  | 44 | 44 | 620109700-015-G |  | CAP,3.3nF,+/-10%,X7R,50V,G,SMD0402 | MURATA ELEC. NORTH AMERICA | GRM155R71H332K | 7 | G | PLTC6,PECC20,PECC21,PECC22,PECC31,PECC32,PECC33 |  |  |  |  |  |  |
|  |  |  |  |  | 44 | 620109700-012-G |  | CAP,3.3nF,+/-10%,X7R,50V,G,SMD0402 | WALSIN TECHNOLOGY CORPORATION | 0402B332K500CT |  | G |  |  |  |  |  |  |  |
|  |  |  |  |  | 44 | 620109700-026-G |  | CAP,3.3nF,+/-10%,X7R,50V,G,SMD0402 | SAMSUNG SEMICONDUCTOR | CL05B332KB5NNNC |  | G |  |  |  |  |  |  |  |
|  |  |  |  | 45 | 45 | 62011HS01-015-G |  | CAP,10uF,+/-10%,X7R,25V,G,SMD1206 | MURATA ELEC. NORTH AMERICA | GRM31CR71E106K | 21 | G | PFCC5,PELC5,PFCC6,PELC6,PFCC7,PELC7,PFCC8,PELC8,PFCC9,PECC23,PECC24,PECC25,PECC26,PECC27,PECC28,PECC34,PECC35,PECC36,PECC37,PECC38,PECC39 |  |  |  |  |  |  |
|  |  |  |  |  | 45 | 62011HS00-026-G |  | CAP,10uF,+/-10%,X7R,25V,G,SMD1206 | SAMSUNG SEMICONDUCTOR | CL31B106KAHNNNE |  | G |  |  |  |  |  |  |  |
|  |  |  |  |  | 45 | 62011HS00-023-G |  | CAP,10uF,+/-10%,X7R,25V,G,SMD1206 | TAIYO ELECTRIC IND.CO.LTD | TMK316B7106KL-TD |  | G |  |  |  |  |  |  |  |
|  |  |  |  | 46 | 46 | 620113A01-015-G | - | CAP,680pF,+/-5%,NPO,50V,G,SMD0402 | MURATA ELEC. NORTH AMERICA | GRM1555C1H681J | 2 | G | PECC42,PECC43 |  |  |  |  |  |  |
|  |  |  |  |  | 46 | 620113A00-012-G |  | CAP,680pF,+/-5%,NPO(C0G),50V,G,SMD0402 | WALSIN TECHNOLOGY CORPORATION | 0402N681J500LT |  | G |  |  |  |  |  |  |  |
|  |  |  |  |  | 46 | 620113A00-025-G |  | CAP,680pF,+/-5%,NPO(C0G),50V,G,SMD0402 | KEMET ELECTRONICS CORPORATION | C0402C681J5GAC |  | G |  |  |  |  |  |  |  |
|  |  |  |  |  | 46 | 620113A00-016-G |  | CAP,680pF,+/-5%,NPO(C0G),50V,G,SMD0402 | TDK ELECTRONICS EUROPE GMBH | C1005C0G1H681JT |  | G |  |  |  |  |  |  |  |
|  |  |  |  | 47 | 47 | 62012G200-015-G | - | CAP,22uF,+/-20%,X6S,4V,G,SMD0603 | MURATA ELEC. NORTH AMERICA | GRM188C80G226M | 12 | G | PECC44,PECC45,PECC46,PECC47,PECC48,PECC49,PECC50,PECC51,PECC52,PECC53,PECC54,PECC55 |  |  |  |  |  |  |
|  |  |  |  |  | 47 | 62012G200-012-G |  | CAP,22uF,+/-20%,X6S,4V,G,SMD0603 | WALSIN TECHNOLOGY CORPORATION | 0603S226M4R0CT |  | G |  |  |  |  |  |  |  |
|  |  |  |  |  | 47 | 62012G200-026-G |  | CAP,22uF,+/-20%,X6S,4V,G,SMD0603 | SAMSUNG SEMICONDUCTOR | CL10X226MR8NUNE |  | G |  |  |  |  |  |  |  |
|  |  |  |  |  | 47 | 62012G200-023-G |  | CAP,22uF,+/-20%,X6S,4V,G,SMD0603 | TAIYO ELECTRIC IND.CO.LTD | AMK107BC6226MA-T |  | G |  |  |  |  |  |  |  |
|  |  |  |  | 48 | 48 | 630330400-088-G | - | IND,150nH@100KHz,+/-10%,51A,304.5uOhm,SHLD,G,SMD | COOPER BUSSMANN, INC. | FP0906R1-R15-R | 2 | G | PECL1,PECL2 |  |  |  |  |  |  |
|  |  |  |  | 49 | 49 | 63035SH00-065-G |  | IND,22nH@100KHz,+/-15%,22A,249.55uOhm,SHLD,G,SMD | DELTA ELECTRONICS INDUSTRIAL CO.,LTD | HCB0439-220 | 1 | G | PECL3 |  |  |  |  |  |  |
|  |  |  |  | 50 | 50 | 61100LQ00-017-G |  | RES,20KOhm,+/-1%,1/16W,G,SMD0402 | KOA SPEER ELECTRONICS, INC. | RN731ETTP2002F50 | 1 | G | PECR1 |  |  |  |  |  |  |
|  |  |  |  |  | 50 | 61100LQ00-011-G |  | RES,20KOhm,+/-1%,1/16W,G,SMD0402 | YAGEO CORPORATION COMPONENT | RT0402FRE0720KL |  | G |  |  |  |  |  |  |  |
|  |  |  |  |  | 50 | 61100LQ00-044-G |  | RES,20KOhm,+/-1%,1/16W,G,SMD0402 | TA-I TECHNOLOGY CO., LTD. | RB04FTS2002 |  | G |  |  |  |  |  |  |  |
|  |  |  |  |  | 50 | 61100LQ00-012-G |  | RES,20KOhm,+/-1%,1/16W,G,SMD0402 | WALSIN TECHNOLOGY CORPORATION | WF04T2002FTL |  | G |  |  |  |  |  |  |  |
|  |  |  |  | 51 | 51 | 61011FP00-017-G |  | RES,113KOhm,+/-1%,1/16W,G,SMD0402 | KOA SPEER ELECTRONICS, INC. | RK73H1ETTP1133F | 2 | G | PECR2,PECR13 |  |  |  |  |  |  |
|  |  |  |  |  | 51 | 61011FP00-011-G |  | RES,113KOhm,+/-1%,1/16W,G,SMD0402 | YAGEO CORPORATION COMPONENT | RC0402FR-07113KL |  | G |  |  |  |  |  |  |  |
|  |  |  |  |  | 51 | 61011FP00-012-G |  | RES,113KOhm,+/-1%,1/16W,G,SMD0402 | WALSIN TECHNOLOGY CORPORATION | WR04X1133FTL |  | G |  |  |  |  |  |  |  |
|  |  |  |  |  | 51 | 61011FP00-044-G |  | RES,113KOhm,+/-1%,1/16W,G,SMD0402 | TA-I TECHNOLOGY CO., LTD. | RM04FTN1133 |  | G |  |  |  |  |  |  |  |
|  |  |  |  | 52 | 52 | 61011HP00-017-G |  | RES,44.2KOhm,+/-1%,1/16W,G,SMD0402 | KOA SPEER ELECTRONICS, INC. | RK73H1ETTP4422F | 1 | G | PECR3 |  |  |  |  |  |  |
|  |  |  |  |  | 52 | 61011HP00-012-G |  | RES,44.2KOhm,+/-1%,1/16W,G,SMD0402 | WALSIN TECHNOLOGY CORPORATION | WR04X4422FTL |  | G |  |  |  |  |  |  |  |
|  |  |  |  |  | 52 | 61011HP00-011-G |  | RES,44.2KOhm,+/-1%,1/16W,G,SMD0402 | YAGEO CORPORATION COMPONENT | RC0402FR-0744K2L |  | G |  |  |  |  |  |  |  |
|  |  |  |  |  | 52 | 61011HP00-044-G |  | RES,44.2KOhm,+/-1%,1/16W,G,SMD0402 | TA-I TECHNOLOGY CO., LTD. | RM04FTN4422 |  | G |  |  |  |  |  |  |  |
|  |  |  |  | 53 | 53 | 61011LH00-017-G |  | RES,9.31KOhm,+/-1%,1/16W,G,SMD0402 | KOA SPEER ELECTRONICS, INC. | RK73H1ETTP9311F | 1 | G | PECR4 |  |  |  |  |  |  |
|  |  |  |  |  | 53 | 61011LH00-011-G |  | RES,9.31KOhm,+/-1%,1/16W,G,SMD0402 | YAGEO CORPORATION COMPONENT | RC0402FR-079K31L |  | G |  |  |  |  |  |  |  |
|  |  |  |  |  | 53 | 61011LH00-012-G |  | RES,9.31KOhm,+/-1%,1/16W,G,SMD0402 | WALSIN TECHNOLOGY CORPORATION | WR04X9311FTL |  | G |  |  |  |  |  |  |  |
|  |  |  |  |  | 53 | 61011LH00-044-G |  | RES,9.31KOhm,+/-1%,1/16W,G,SMD0402 | TA-I TECHNOLOGY CO., LTD. | RM04FTN9311 |  | G |  |  |  |  |  |  |  |
|  |  |  |  | 54 | 54 | 61011H600-017-G |  | RES,16.5KOhm,+/-1%,1/16W,G,SMD0402 | KOA SPEER ELECTRONICS, INC. | RK73H1ETTP1652F | 1 | G | PECR5 |  |  |  |  |  |  |
|  |  |  |  |  | 54 | 61011H600-011-G |  | RES,16.5KOhm,+/-1%,1/16W,G,SMD0402 | YAGEO CORPORATION COMPONENT | RC0402FR-0716K5L |  | G |  |  |  |  |  |  |  |
|  |  |  |  |  | 54 | 61011H600-012-G |  | RES,16.5KOhm,+/-1%,1/16W,G,SMD0402 | WALSIN TECHNOLOGY CORPORATION | WR04X1652FTL |  | G |  |  |  |  |  |  |  |
|  |  |  |  | 55 | 55 | 610127Q00-017-G |  | RES,357KOhm,+/-1%,1/16W,G,SMD0402 | KOA SPEER ELECTRONICS, INC. | RK73H1ETTP3573F | 1 | G | PECR6 |  |  |  |  |  |  |
|  |  |  |  |  | 55 | 610127Q00-012-G |  | RES,357KOhm,+/-1%,1/16W,G,SMD0402 | WALSIN TECHNOLOGY CORPORATION | WR04X3573FTL |  | G |  |  |  |  |  |  |  |
|  |  |  |  |  | 55 | 610127Q00-011-G |  | RES,357KOhm,+/-1%,1/16W,G,SMD0402 | YAGEO CORPORATION COMPONENT | RC0402FR-07357KL |  | G |  |  |  |  |  |  |  |
|  |  |  |  |  | 55 | 610127Q00-044-G |  | RES,357KOhm,+/-1%,1/16W,G,SMD0402 | TA-I TECHNOLOGY CO., LTD. | RM04FTN3573 |  | G |  |  |  |  |  |  |  |
|  |  |  |  | 56 | 56 | 61011MG00-017-G |  | RES,42.2KOhm,+/-1%,1/16W,G,SMD0402 | KOA SPEER ELECTRONICS, INC. | RK73H1ETTP4222F | 1 | G | PECR7 |  |  |  |  |  |  |
|  |  |  |  |  | 56 | 61011MG00-012-G |  | RES,42.2KOhm,+/-1%,1/16W,G,SMD0402 | WALSIN TECHNOLOGY CORPORATION | WR04X4222FTL |  | G |  |  |  |  |  |  |  |
|  |  |  |  |  | 56 | 61011MG00-011-G |  | RES,42.2KOhm,+/-1%,1/16W,G,SMD0402 | YAGEO CORPORATION COMPONENT | RC0402FR-0742K2L |  | G |  |  |  |  |  |  |  |
|  |  |  |  |  | 56 | 61011MG00-044-G |  | RES,42.2KOhm,+/-1%,1/16W,G,SMD0402 | TA-I TECHNOLOGY CO., LTD. | RM04FTN4222 |  | G |  |  |  |  |  |  |  |
|  |  |  |  | 57 | 57 | 61011AQ00-017-G |  | RES,30.1KOhm,+/-1%,1/16W,G,SMD0402 | KOA SPEER ELECTRONICS, INC. | RK73H1ETTP3012F | 2 | G | PECR8,PECR12 |  |  |  |  |  |  |
|  |  |  |  |  | 57 | 61011AQ00-012-G |  | RES,30.1KOhm,+/-1%,1/16W,G,SMD0402 | WALSIN TECHNOLOGY CORPORATION | WR04X3012FTL |  | G |  |  |  |  |  |  |  |
|  |  |  |  |  | 57 | 61011AQ00-011-G |  | RES,30.1KOhm,+/-1%,1/16W,G,SMD0402 | YAGEO CORPORATION COMPONENT | RC0402FR-0730K1L |  | G |  |  |  |  |  |  |  |
|  |  |  |  |  | 57 | 61011AQ00-044-G |  | RES,30.1KOhm,+/-1%,1/16W,G,SMD0402 | TA-I TECHNOLOGY CO., LTD. | RM04FTN3012 |  | G |  |  |  |  |  |  |  |
|  |  |  |  | 58 | 58 | 61100K600-044-G |  | RES,24KOhm,+/-0.1%,1/16W,G,SMD0402 | TA-I TECHNOLOGY CO., LTD. | RB04BTP2402 | 1 | G | PECR9 |  |  |  |  |  |  |
|  |  |  |  | 59 | 59 | 610116G00-017-G | - | RES,150KOhm,+/-1%,1/16W,G,SMD0402 | KOA SPEER ELECTRONICS, INC. | RK73H1ETTP1503F | 1 | G | PECR10 |  |  |  |  |  |  |
|  |  |  |  |  | 59 | 610116G00-011-G |  | RES,150KOhm,+/-1%,1/16W,G,SMD0402 | YAGEO CORPORATION COMPONENT | RC0402FR-07150KL |  | G |  |  |  |  |  |  |  |
|  |  |  |  |  | 59 | 610116G00-012-G |  | RES,150KOhm,+/-1%,1/16W,G,SMD0402 | WALSIN TECHNOLOGY CORPORATION | WR04X1503FTL |  | G |  |  |  |  |  |  |  |
|  |  |  |  |  | 59 | 610116G00-044-G |  | RES,150KOhm,+/-1%,1/16W,G,SMD0402 | TA-I TECHNOLOGY CO., LTD. | RM04FTN1503 |  | G |  |  |  |  |  |  |  |
|  |  |  |  | 60 | 60 | 610114H00-017-G | - | RES,20KOhm,+/-1%,1/16W,G,SMD0402 | KOA SPEER ELECTRONICS, INC. | RK73H1ETTP2002F | 2 | G | PELR10,PECR11 |  |  |  |  |  |  |
|  |  |  |  |  | 60 | 610114H00-011-G |  | RES,20KOhm,+/-1%,1/16W,G,SMD0402 | YAGEO CORPORATION COMPONENT | RC0402FR-0720KL |  | G |  |  |  |  |  |  |  |
|  |  |  |  |  | 60 | 610114H00-012-G |  | RES,20KOhm,+/-1%,1/16W,G,SMD0402 | WALSIN TECHNOLOGY CORPORATION | WR04X2002FTL |  | G |  |  |  |  |  |  |  |
|  |  |  |  |  | 60 | 610114H00-044-G |  | RES,20KOhm,+/-1%,1/16W,G,SMD0402 | TA-I TECHNOLOGY CO., LTD. | RM04FTN2002 |  | G |  |  |  |  |  |  |  |
|  |  |  |  |  | 60 | 610114H00-024-G |  | RES,20KOhm,+/-1%,1/16W,G,SMD0402 | PANASONIC INDUSTRIAL CO.,LTD. | ERJ2RKF2002x |  | G |  |  |  |  |  |  |  |
|  |  |  |  |  | 60 | 610114H00-030-G |  | RES,20KOhm,+/-1%,1/16W,G,SMD0402 | ROHM CORPORATION | MCR01MZPF2002 |  | G |  |  |  |  |  |  |  |
|  |  |  |  |  | 60 | 610114H04-029-G |  | RES,20KOhm,+/-1%,1/16W,G,SMD0402 | VISHAY ENTER TECHNO LOGY.INC | CRCW040220K0FKEDC |  | G |  |  |  |  |  |  |  |
|  |  |  |  | 61 | 61 | 61011TN00-017-G |  | RES,39KOhm,+/-1%,1/16W,G,SMD0402 | KOA SPEER ELECTRONICS, INC. | RK73H1ETTP3902F | 1 | G | PECR14 |  |  |  |  |  |  |
|  |  |  |  |  | 61 | 61011TN00-011-G |  | RES,39KOhm,+/-1%,1/16W,G,SMD0402 | YAGEO CORPORATION COMPONENT | RC0402FR-0739KL |  | G |  |  |  |  |  |  |  |
|  |  |  |  |  | 61 | 61011TN00-012-G |  | RES,39KOhm,+/-1%,1/16W,G,SMD0402 | WALSIN TECHNOLOGY CORPORATION | WR04X3902FTL |  | G |  |  |  |  |  |  |  |
|  |  |  |  |  | 61 | 61011TN00-044-G |  | RES,39KOhm,+/-1%,1/16W,G,SMD0402 | TA-I TECHNOLOGY CO., LTD. | RM04FTN3902 |  | G |  |  |  |  |  |  |  |
|  |  |  |  | 62 | 62 | 61010L300-017-G | - | RES,1KOhm,+/-1%,1/16W,G,SMD0402 | KOA SPEER ELECTRONICS, INC. | RK73H1ETTP1001F | 24 | G | PECR16,PECR25,R206,R207,R216,R217,R226,R227,R378,R379,R380,R387,R388,R389,R390,R403,R433,R434,R435,R438,R1401,R1402,R1537,R1538 |  |  |  |  |  |  |
|  |  |  |  |  | 62 | 61010L300-012-G |  | RES,1KOhm,+/-1%,1/16W,G,SMD0402 | WALSIN TECHNOLOGY CORPORATION | WR04X1001FTL |  | G |  |  |  |  |  |  |  |
|  |  |  |  |  | 62 | 61010L300-011-G |  | RES,1KOhm,+/-1%,1/16W,G,SMD0402 | YAGEO CORPORATION COMPONENT | RC0402FR-071KL |  | G |  |  |  |  |  |  |  |
|  |  |  |  |  | 62 | 61010L300-044-G |  | RES,1KOhm,+/-1%,1/16W,G,SMD0402 | TA-I TECHNOLOGY CO., LTD. | RM04FTN1001 |  | G |  |  |  |  |  |  |  |
|  |  |  |  |  | 62 | 61010L300-024-G |  | RES,1KOhm,+/-1%,1/16W,G,SMD0402 | PANASONIC INDUSTRIAL CO.,LTD. | ERJ2RKF1001X |  | G |  |  |  |  |  |  |  |
|  |  |  |  |  | 62 | 61010L300-029-G |  | RES,1KOhm,+/-1%,1/16W,G,SMD0402 | VISHAY ENTER TECHNO LOGY.INC | CRCW04021K00FKED |  | G |  |  |  |  |  |  |  |
|  |  |  |  | 63 | 63 | 610107A00-017-G | - | RES,0 Ohm,+/-5%,1/16W,G,SMD0402 | KOA SPEER ELECTRONICS, INC. | RK73Z1ETTP | 79 | G | PLTR1,PSLR2,PSGR2,PSCR2,PFCR2,PELR2,PFCR3,PSCR7,PELR7,PSRR8,PSCR8,PSRR9,PSLR9,PSGR9,PFCR9,PELR9,R11,PFCR11,PSLR13,PSCR14,PSRR15,PSLR15,PSGR15,PELR15,PELR16,PFCR17,PELR17,PSRR18,PSLR18,PSGR18,PFCR18,PSCR22,PECR22,PECR23,PECR28,PECR30,PECR37,PECR38,PECR41,PECR42,PECR44,PECR52,PECR53,R131,R132,R133,R135,R137,R189,R198,R204,R205,R212,R213,R214,R215,R220,R221,R222,R223,R237,R250,R1387,R1388,R1410,R1441,R1445,R1513,R1514,R1515,R1516,R1520,R1524,R1535,R1536,R1540,PSCR3001,PSCR3002,PSCR3003 |  |  |  |  |  |  |
|  |  |  |  |  | 63 | 610107A00-012-G |  | RES,0 Ohm,+/-5%,1/16W,G,SMD0402 | WALSIN TECHNOLOGY CORPORATION | WR04X000PTL |  | G |  |  |  |  |  |  |  |
|  |  |  |  |  | 63 | 610107A00-011-G |  | RES,0 Ohm,+/-5%,1/16W,G,SMD0402 | YAGEO CORPORATION COMPONENT | RC0402JR-070RL |  | G |  |  |  |  |  |  |  |
|  |  |  |  |  | 63 | 610107A00-044-G |  | RES,0 Ohm,+/-5%,1/16W,G,SMD0402 | TA-I TECHNOLOGY CO., LTD. | RM04JTN0 |  | G |  |  |  |  |  |  |  |
|  |  |  |  |  | 63 | 610107A00-024-G |  | RES,0 Ohm,+/-5%,1/16W,G,SMD0402 | PANASONIC INDUSTRIAL CO.,LTD. | ERJ2GE0R00X |  | G |  |  |  |  |  |  |  |
|  |  |  |  |  | 63 | 610107A00-029-G |  | RES,0 Ohm,+/-5%,1/16W,G,SMD0402 | VISHAY ENTER TECHNO LOGY.INC | CRCW04020000Z0ED |  | G |  |  |  |  |  |  |  |
|  |  |  |  | 64 | 64 | 61010LE00-017-G |  | RES,12KOhm,+/-1%,1/16W,G,SMD0402 | KOA SPEER ELECTRONICS, INC. | RK73H1ETTP1202F | 1 | G | PECR24 |  |  |  |  |  |  |
|  |  |  |  |  | 64 | 61010LE00-011-G |  | RES,12KOhm,+/-1%,1/16W,G,SMD0402 | YAGEO CORPORATION COMPONENT | RC0402FR-0712KL |  | G |  |  |  |  |  |  |  |
|  |  |  |  |  | 64 | 61010LE00-012-G |  | RES,12KOhm,+/-1%,1/16W,G,SMD0402 | WALSIN TECHNOLOGY CORPORATION | WR04X1202FTL |  | G |  |  |  |  |  |  |  |
|  |  |  |  |  | 64 | 61010LE00-044-G |  | RES,12KOhm,+/-1%,1/16W,G,SMD0402 | TA-I TECHNOLOGY CO., LTD. | RM04FTN1202 |  | G |  |  |  |  |  |  |  |
|  |  |  |  | 65 | 65 | 610114S00-017-G | - | RES,4.99KOhm,+/-1%,1/16W,G,SMD0402 | KOA SPEER ELECTRONICS, INC. | RK73H1ETTP4991F | 3 | G | PSRR3,PSCR9,PECR26 |  |  |  |  |  |  |
|  |  |  |  |  | 65 | 610114S00-012-G |  | RES,4.99KOhm,+/-1%,1/16W,G,SMD0402 | WALSIN TECHNOLOGY CORPORATION | WR04X4991FTL |  | G |  |  |  |  |  |  |  |
|  |  |  |  |  | 65 | 610114S00-011-G |  | RES,4.99KOhm,+/-1%,1/16W,G,SMD0402 | YAGEO CORPORATION COMPONENT | RC0402FR-074K99L |  | G |  |  |  |  |  |  |  |
|  |  |  |  |  | 65 | 610114S00-044-G |  | RES,4.99KOhm,+/-1%,1/16W,G,SMD0402 | TA-I TECHNOLOGY CO., LTD. | RM04FTN4991 |  | G |  |  |  |  |  |  |  |
|  |  |  |  |  | 65 | 610114S00-024-G |  | RES,4.99KOhm,+/-1%,1/16W,G,SMD0402 | PANASONIC INDUSTRIAL CO.,LTD. | ERJ2RKF4991X |  | G |  |  |  |  |  |  |  |
|  |  |  |  | 66 | 66 | 61011GY00-017-G | - | RES,2.43KOhm,+/-1%,1/16W,G,SMD0402 | KOA SPEER ELECTRONICS, INC. | RK73H1ETTP2431F | 1 | G | PECR27 |  |  |  |  |  |  |
|  |  |  |  |  | 66 | 61011GY00-012-G |  | RES,2.43KOhm,+/-1%,1/16W,G,SMD0402 | WALSIN TECHNOLOGY CORPORATION | WR04X2431FTL |  | G |  |  |  |  |  |  |  |
|  |  |  |  |  | 66 | 61011GY00-011-G |  | RES,2.43KOhm,+/-1%,1/16W,G,SMD0402 | YAGEO CORPORATION COMPONENT | RC0402FR-072K43L |  | G |  |  |  |  |  |  |  |
|  |  |  |  |  | 66 | 61011GY00-044-G |  | RES,2.43KOhm,+/-1%,1/16W,G,SMD0402 | TA-I TECHNOLOGY CO., LTD. | RM04FTN2431 |  | G |  |  |  |  |  |  |  |
|  |  |  |  | 67 | 67 | 61011C300-017-G |  | RES,2.2 Ohm,+/-1%,1/16W,G,SMD0402 | KOA SPEER ELECTRONICS, INC. | RK73H1ETTP2R20F | 1 | G | PECR29 |  |  |  |  |  |  |
|  |  |  |  |  | 67 | 61011C300-012-G |  | RES,2.2 Ohm,+/-1%,1/16W,G,SMD0402 | WALSIN TECHNOLOGY CORPORATION | WR04W2R20FTL |  | G |  |  |  |  |  |  |  |
|  |  |  |  |  | 67 | 61011C300-011-G |  | RES,2.2 Ohm,+/-1%,1/16W,G,SMD0402 | YAGEO CORPORATION COMPONENT | RC0402FR-072R2L |  | G |  |  |  |  |  |  |  |
|  |  |  |  |  | 67 | 61011C300-044-G |  | RES,2.2 Ohm,+/-1%,1/16W,G,SMD0402 | TA-I TECHNOLOGY CO., LTD. | RM04FTN2R20 |  | G |  |  |  |  |  |  |  |
|  |  |  |  | 68 | 68 | 610108300-017-G | - | RES,0 Ohm,+/-5%,1/10W,G,SMD0603 | KOA SPEER ELECTRONICS, INC. | RK73Z1JTTD | 2 | G | PECR31,PECR32 |  |  |  |  |  |  |
|  |  |  |  |  | 68 | 610108300-012-G |  | RES,0 Ohm,+/-5%,1/10W,G,SMD0603 | WALSIN TECHNOLOGY CORPORATION | WR06X000PTL |  | G |  |  |  |  |  |  |  |
|  |  |  |  |  | 68 | 610108300-011-G |  | RES,0 Ohm,+/-5%,1/10W,G,SMD0603 | YAGEO CORPORATION COMPONENT | RC0603JR-070RL |  | G |  |  |  |  |  |  |  |
|  |  |  |  |  | 68 | 610108300-044-G |  | RES,0 Ohm,+/-5%,1/10W,G,SMD0603 | TA-I TECHNOLOGY CO., LTD. | RM06JTN0 |  | G |  |  |  |  |  |  |  |
|  |  |  |  |  | 68 | 610108300-024-G |  | RES,0 Ohm,+/-5%,1/10W,G,SMD0603 | PANASONIC INDUSTRIAL CO.,LTD. | ERJ3GEY0R00V |  | G |  |  |  |  |  |  |  |
|  |  |  |  | 69 | 69 | 610113800-017-G | - | RES,10 Ohm,+/-1%,1/16W,G,SMD0402 | KOA SPEER ELECTRONICS, INC. | RK73H1ETTP10R0F | 13 | G | PFCR4,PECR33,PECR34,R105,R106,R107,R108,R109,R110,R111,R112,R113,R114 |  |  |  |  |  |  |
|  |  |  |  |  | 69 | 610113800-012-G |  | RES,10 Ohm,+/-1%,1/16W,G,SMD0402 | WALSIN TECHNOLOGY CORPORATION | WR04X10R0FTL |  | G |  |  |  |  |  |  |  |
|  |  |  |  |  | 69 | 610113800-011-G |  | RES,10 Ohm,+/-1%,1/16W,G,SMD0402 | YAGEO CORPORATION COMPONENT | RC0402FR-0710RL |  | G |  |  |  |  |  |  |  |
|  |  |  |  |  | 69 | 610113800-044-G |  | RES,10 Ohm,+/-1%,1/16W,G,SMD0402 | TA-I TECHNOLOGY CO., LTD. | RM04FTN10R0 |  | G |  |  |  |  |  |  |  |
|  |  |  |  | 70 | 70 | 61011HA00-017-G |  | RES,1 Ohm,+/-1%,1/16W,G,SMD0402 | KOA SPEER ELECTRONICS, INC. | RK73H1ETTP1R00F | 7 | G | PSCR4,PSRR5,PSLR5,PSGR5,PFCR7,PECR39,PECR40 |  |  |  |  |  |  |
|  |  |  |  |  | 70 | 61011HA00-012-G |  | RES,1 Ohm,+/-1%,1/16W,G,SMD0402 | WALSIN TECHNOLOGY CORPORATION | WR04W1R00FTL |  | G |  |  |  |  |  |  |  |
|  |  |  |  |  | 70 | 61011HA00-011-G |  | RES,1 Ohm,+/-1%,1/16W,G,SMD0402 | YAGEO CORPORATION COMPONENT | RC0402FR-071RL |  | G |  |  |  |  |  |  |  |
|  |  |  |  |  | 70 | 61011HA00-044-G |  | RES,1 Ohm,+/-1%,1/16W,G,SMD0402 | TA-I TECHNOLOGY CO., LTD. | RM04FTN1R00 |  | G |  |  |  |  |  |  |  |
|  |  |  |  |  | 70 | 61011HA00-029-G |  | RES,1 Ohm,+/-1%,1/16W,G,SMD0402 | VISHAY ENTER TECHNO LOGY.INC | CRCW04021R00FNED |  | G |  |  |  |  |  |  |  |
|  |  |  |  | 71 | 71 | 61010FE00-017-G | - | RES,100 Ohm,+/-1%,1/16W,G,SMD0402 | KOA SPEER ELECTRONICS, INC. | RK73H1ETTP1000F | 30 | G | PECR43,R73,R74,R96,R1380,R1449,R1450,R1455,R1456,R1457,R1458,R1459,R1460,R1461,R1462,R1463,R1464,R1465,R1466,R1467,R1468,R1469,R1470,R1471,R1472,R1473,R1474,R1475,R1476,R1477 |  |  |  |  |  |  |
|  |  |  |  |  | 71 | 61010FE00-012-G |  | RES,100 Ohm,+/-1%,1/16W,G,SMD0402 | WALSIN TECHNOLOGY CORPORATION | WR04X1000FTL |  | G |  |  |  |  |  |  |  |
|  |  |  |  |  | 71 | 61010FE00-011-G |  | RES,100 Ohm,+/-1%,1/16W,G,SMD0402 | YAGEO CORPORATION COMPONENT | RC0402FR-07100RL |  | G |  |  |  |  |  |  |  |
|  |  |  |  |  | 71 | 61010FE00-044-G |  | RES,100 Ohm,+/-1%,1/16W,G,SMD0402 | TA-I TECHNOLOGY CO., LTD. | RM04FTN1000 |  | G |  |  |  |  |  |  |  |
|  |  |  |  | 72 | 72 | 610125N00-017-G |  | RES,3.3 Ohm,+/-1%,1/16W,G,SMD0402 | KOA SPEER ELECTRONICS, INC. | RK73H1ETTP3R30F | 2 | G | PECR45,PECR46 |  |  |  |  |  |  |
|  |  |  |  |  | 72 | 610125N00-012-G |  | RES,3.3 Ohm,+/-1%,1/16W,G,SMD0402 | WALSIN TECHNOLOGY CORPORATION | WR04W3R30FTL |  | G |  |  |  |  |  |  |  |
|  |  |  |  |  | 72 | 610125N00-011-G |  | RES,3.3 Ohm,+/-1%,1/16W,G,SMD0402 | YAGEO CORPORATION COMPONENT | RC0402FR-073R3L |  | G |  |  |  |  |  |  |  |
|  |  |  |  |  | 72 | 610125N00-044-G |  | RES,3.3 Ohm,+/-1%,1/16W,G,SMD0402 | TA-I TECHNOLOGY CO., LTD. | RM04FTN3R30 |  | G |  |  |  |  |  |  |  |
|  |  |  |  | 73 | 73 | 610101100-017-G |  | RES,1 Ohm,+/-1%,1/10W,G,SMD0603 | KOA SPEER ELECTRONICS, INC. | RK73H1JTTD1R00F | 9 | G | PELR4,PELR11,PELR13,PFCR14,PFCR16,PECR47,PECR48,PECR49,PECR50 |  |  |  |  |  |  |
|  |  |  |  |  | 73 | 610101100-011-G |  | RES,1 Ohm,+/-1%,1/10W,G,SMD0603 | YAGEO CORPORATION COMPONENT | RC0603FR-071RL |  | G |  |  |  |  |  |  |  |
|  |  |  |  |  | 73 | 610101100-012-G |  | RES,1 Ohm,+/-1%,1/10W,G,SMD0603 | WALSIN TECHNOLOGY CORPORATION | WR06W1R00FTL |  | G |  |  |  |  |  |  |  |
|  |  |  |  |  | 73 | 610101100-044-G |  | RES,1 Ohm,+/-1%,1/10W,G,SMD0603 | TA-I TECHNOLOGY CO., LTD. | RM06FTN1R00 |  | G |  |  |  |  |  |  |  |
|  |  |  |  | 74 | 74 | 32022VJ00-183-G |  | IC,PWM Controller,TPS53641RSBR,G,QFN-40,SMD | TEXAS INSTRUMENTS | TPS53641RSBR | 1 | G | PECU1 |  |  |  |  |  |  |
|  |  |  |  | 75 | 75 | 320240000-183-G |  | IC,PWM Controller,CSD95472Q5MC,G,SON-13,SMD | TEXAS INSTRUMENTS | CSD95472Q5MC | 2 | G | PECU2,PECU3 |  |  |  |  |  |  |
|  |  |  |  | 76 | 76 | 62012PT00-015-G | - | CAP,22uF,+/-20%,X6S,16V,G,SMD0805 | MURATA ELEC. NORTH AMERICA | GRM21BC81C226M | 15 | G | PSRC7,PLTC7,PSRC8,PLTC8,PLTC9,PLTC10,PSRC11,PSRC12,PELC12,PELC13,PELC14,PSRC15,PELC15,PELC18,PELC19 |  |  |  |  |  |  |
|  |  |  |  |  | 76 | 62012PT00-023-G |  | CAP,22uF,+/-20%,X6S,16V,G,SMD0805 | TAIYO ELECTRIC IND.CO.LTD | EDK212BC6226MG-T |  | G |  |  |  |  |  |  |  |
|  |  |  |  | 77 | 77 | 62011G000-015-G | - | CAP,1uF,+/-10%,X5R,16V,G,SMD0402 | MURATA ELEC. NORTH AMERICA | GRM155R61C105K | 1 | G | PELC16 |  |  |  |  |  |  |
|  |  |  |  |  | 77 | 62011G000-026-G |  | CAP,1uF,+/-10%,X5R,16V,G,SMD0402 | SAMSUNG SEMICONDUCTOR | CL05A105KO5NNNC |  | G |  |  |  |  |  |  |  |
|  |  |  |  |  | 77 | 62011G000-023-G |  | CAP,1uF,+/-10%,X5R,16V,G,SMD0402 | TAIYO ELECTRIC IND.CO.LTD | EMK105BJ105KV-F |  | G |  |  |  |  |  |  |  |
|  |  |  |  |  | 77 | 62011G000-012-G |  | CAP,1uF,+/-10%,X5R,16V,G,SMD0402 | WALSIN TECHNOLOGY CORPORATION | 0402X105K160CT |  | G |  |  |  |  |  |  |  |
|  |  |  |  | 78 | 78 | 72010RE00-015-G |  | FB,26 Ohm@100MHz,+/-25%,6A,7mOhm,G,SMD0603 | MURATA ELEC. NORTH AMERICA | BLM18KG260TN1D | 8 | G | PSRL1,PSLL1,PSGL1,PLTL1,PFCL1,PELL1,PELL3,PELL4 |  |  |  |  |  |  |
|  |  |  |  | 79 | 79 | 63033RJ00-15A-G |  | IND,4.7uH@100KHz,+/-20%,3.5A,65mOhm,SHLD,G,SMD | The Inter-Technical Group, Inc. | SMHC2011-4R7MHF | 1 | G | PELL2 |  |  |  |  |  |  |
|  |  |  |  | 80 | 80 | 611003200-044-G |  | RES,10KOhm,+/-0.1%,1/16W,G,SMD0402 | TA-I TECHNOLOGY CO., LTD. | RB04BTP1002 | 2 | G | PELR3,PFCR5 |  |  |  |  |  |  |
|  |  |  |  | 81 | 81 | 61100UT00-044-G |  | RES,20.5KOhm,+/-0.1%,1/16W,G,SMD0402 | TA-I TECHNOLOGY CO., LTD. | RB04BTP2052 | 1 | G | PELR5 |  |  |  |  |  |  |
|  |  |  |  | 82 | 82 | 61010LA00-017-G | - | RES,4.7KOhm,+/-1%,1/16W,G,SMD0402 | KOA SPEER ELECTRONICS, INC. | RK73H1ETTP4701F | 8 | G | PSCR1,PELR6,PFCR8,R229,R230,R251,R252,R1539 |  |  |  |  |  |  |
|  |  |  |  |  | 82 | 61010LA00-012-G |  | RES,4.7KOhm,+/-1%,1/16W,G,SMD0402 | WALSIN TECHNOLOGY CORPORATION | WR04X4701FTL |  | G |  |  |  |  |  |  |  |
|  |  |  |  |  | 82 | 61010LA00-011-G |  | RES,4.7KOhm,+/-1%,1/16W,G,SMD0402 | YAGEO CORPORATION COMPONENT | RC0402FR-074K7L |  | G |  |  |  |  |  |  |  |
|  |  |  |  |  | 82 | 61010LA00-044-G |  | RES,4.7KOhm,+/-1%,1/16W,G,SMD0402 | TA-I TECHNOLOGY CO., LTD. | RM04FTN4701 |  | G |  |  |  |  |  |  |  |
|  |  |  |  | 83 | 83 | 61011UM00-017-G | - | RES,240KOhm,+/-1%,1/16W,G,SMD0402 | KOA SPEER ELECTRONICS, INC. | RK73H1ETTP2403F | 2 | G | PELR12,PFCR13 |  |  |  |  |  |  |
|  |  |  |  |  | 83 | 61011UM00-011-G |  | RES,240KOhm,+/-1%,1/16W,G,SMD0402 | YAGEO CORPORATION COMPONENT | RC0402FR-07240KL |  | G |  |  |  |  |  |  |  |
|  |  |  |  |  | 83 | 61011UM00-012-G |  | RES,240KOhm,+/-1%,1/16W,G,SMD0402 | WALSIN TECHNOLOGY CORPORATION | WR04X2403FTL |  | G |  |  |  |  |  |  |  |
|  |  |  |  |  | 83 | 61011UM00-044-G |  | RES,240KOhm,+/-1%,1/16W,G,SMD0402 | TA-I TECHNOLOGY CO., LTD. | RM04FTN2403 |  | G |  |  |  |  |  |  |  |
|  |  |  |  | 84 | 84 | 61011YJ00-017-G |  | RES,71.5KOhm,+/-1%,1/16W,G,SMD0402 | KOA SPEER ELECTRONICS, INC. | RK73H1ETTP7152F | 2 | G | PELR14,PFCR15 |  |  |  |  |  |  |
|  |  |  |  |  | 84 | 61011YJ00-011-G |  | RES,71.5KOhm,+/-1%,1/16W,G,SMD0402 | YAGEO CORPORATION COMPONENT | RC0402FR-0771K5L |  | G |  |  |  |  |  |  |  |
|  |  |  |  |  | 84 | 61011YJ00-012-G |  | RES,71.5KOhm,+/-1%,1/16W,G,SMD0402 | WALSIN TECHNOLOGY CORPORATION | WR04X7152FTL |  | G |  |  |  |  |  |  |  |
|  |  |  |  |  | 84 | 61011YJ00-044-G |  | RES,71.5KOhm,+/-1%,1/16W,G,SMD0402 | TA-I TECHNOLOGY CO., LTD. | RM04FTN7152 |  | G |  |  |  |  |  |  |  |
|  |  |  |  | 85 | 85 | 32013BY00-183-G |  | IC,Regulator,TPS53513RVER,8A,ADJ,G,QFN-28,SMD | TEXAS INSTRUMENTS | TPS53513RVER | 1 | G | PELU1 |  |  |  |  |  |  |
|  |  |  |  | 86 | 86 | 63033JL00-15A-G |  | IND,470nH@100KHz,+/-20%,13.5A,4.2mOhm,SHLD,G,SMD | The Inter-Technical Group, Inc. | SMHC2511-R47MHF | 1 | G | PFCL2 |  |  |  |  |  |  |
|  |  |  |  | 87 | 87 | 610116N00-017-G |  | RES,5.1KOhm,+/-1%,1/16W,G,SMD0402 | KOA SPEER ELECTRONICS, INC. | RK73H1ETTP5101F | 1 | G | PFCR6 |  |  |  |  |  |  |
|  |  |  |  |  | 87 | 610116N00-011-G |  | RES,5.1KOhm,+/-1%,1/16W,G,SMD0402 | YAGEO CORPORATION COMPONENT | RC0402FR-075K1L |  | G |  |  |  |  |  |  |  |
|  |  |  |  |  | 87 | 610116N00-012-G |  | RES,5.1KOhm,+/-1%,1/16W,G,SMD0402 | WALSIN TECHNOLOGY CORPORATION | WR04X5101FTL |  | G |  |  |  |  |  |  |  |
|  |  |  |  |  | 87 | 610116N00-044-G |  | RES,5.1KOhm,+/-1%,1/16W,G,SMD0402 | TA-I TECHNOLOGY CO., LTD. | RM04FTN5101 |  | G |  |  |  |  |  |  |  |
|  |  |  |  | 88 | 88 | 61011VM00-017-G | - | RES,57.6KOhm,+/-1%,1/16W,G,SMD0402 | KOA SPEER ELECTRONICS, INC. | RK73H1ETTP5762F | 1 | G | PFCR12 |  |  |  |  |  |  |
|  |  |  |  |  | 88 | 61011VM00-011-G |  | RES,57.6KOhm,+/-1%,1/16W,G,SMD0402 | YAGEO CORPORATION COMPONENT | RC0402FR-0757K6L |  | G |  |  |  |  |  |  |  |
|  |  |  |  |  | 88 | 61011VM00-012-G |  | RES,57.6KOhm,+/-1%,1/16W,G,SMD0402 | WALSIN TECHNOLOGY CORPORATION | WR04X5762FTL |  | G |  |  |  |  |  |  |  |
|  |  |  |  |  | 88 | 61011VM00-044-G |  | RES,57.6KOhm,+/-1%,1/16W,G,SMD0402 | TA-I TECHNOLOGY CO., LTD. | RM04FTN5762 |  | G |  |  |  |  |  |  |  |
|  |  |  |  | 89 | 89 | 320143Y00-183-G | - | IC,Regulator,TPS548A20RVER,ADJ,15A,G,VQFN-28,SMD | TEXAS INSTRUMENTS | TPS548A20RVER | 1 | G | PFCU1 |  |  |  |  |  |  |
|  |  |  |  | 90 | 90 | 62012T500-015-G |  | CAP,22uF,+/-20%,X7S,25V,G,SMD1206 | MURATA ELEC. NORTH AMERICA | GRM31CC71E226ME11L | 18 | G | PSRC2,PSLC2,PSGC2,PLTC2,PLTC3,PSCC6,PSCC7,PSCC8,PSCC9,PSRC17,PSLC17,PSGC17,PSRC18,PSLC18,PSGC18,PSRC19,PSCC3005,PSCC3009 |  |  |  |  |  |  |
|  |  |  |  | 91 | 91 | 61011FG00-017-G |  | RES,107KOhm,+/-1%,1/16W,G,SMD0402 | KOA SPEER ELECTRONICS, INC. | RK73H1ETTP1073F | 1 | G | PLTR2 |  |  |  |  |  |  |
|  |  |  |  |  | 91 | 61011FG00-012-G |  | RES,107KOhm,+/-1%,1/16W,G,SMD0402 | WALSIN TECHNOLOGY CORPORATION | WR04X1073FTL |  | G |  |  |  |  |  |  |  |
|  |  |  |  |  | 91 | 61011FG00-011-G |  | RES,107KOhm,+/-1%,1/16W,G,SMD0402 | YAGEO CORPORATION COMPONENT | RC0402FR-07107KL |  | G |  |  |  |  |  |  |  |
|  |  |  |  |  | 91 | 61011FG00-044-G |  | RES,107KOhm,+/-1%,1/16W,G,SMD0402 | TA-I TECHNOLOGY CO., LTD. | RM04FTN1073 |  | G |  |  |  |  |  |  |  |
|  |  |  |  | 92 | 92 | 610118700-017-G |  | RES,51.1KOhm,+/-1%,1/16W,G,SMD0402 | KOA SPEER ELECTRONICS, INC. | RK73H1ETTP5112F | 1 | G | PLTR3 |  |  |  |  |  |  |
|  |  |  |  |  | 92 | 610118700-012-G |  | RES,51.1KOhm,+/-1%,1/16W,G,SMD0402 | WALSIN TECHNOLOGY CORPORATION | WR04X5112FTL |  | G |  |  |  |  |  |  |  |
|  |  |  |  |  | 92 | 610118700-011-G |  | RES,51.1KOhm,+/-1%,1/16W,G,SMD0402 | YAGEO CORPORATION COMPONENT | RC0402FR-0751K1L |  | G |  |  |  |  |  |  |  |
|  |  |  |  |  | 92 | 610118700-044-G |  | RES,51.1KOhm,+/-1%,1/16W,G,SMD0402 | TA-I TECHNOLOGY CO., LTD. | RM04FTN5112 |  | G |  |  |  |  |  |  |  |
|  |  |  |  | 93 | 93 | 611004M00-017-G |  | RES,16.5KOhm,+/-0.1%,1/16W,G,SMD0402 | KOA SPEER ELECTRONICS, INC. | RN731ETTP1652B25 | 3 | G | PLTR4,PSRR17,PSLR17 |  |  |  |  |  |  |
|  |  |  |  | 94 | 94 | 610119P00-017-G | - | RES,5.11KOhm,+/-1%,1/16W,G,SMD0402 | KOA SPEER ELECTRONICS, INC. | RK73H1ETTP5111F | 1 | G | PLTR5 |  |  |  |  |  |  |
|  |  |  |  |  | 94 | 610119P00-012-G |  | RES,5.11KOhm,+/-1%,1/16W,G,SMD0402 | WALSIN TECHNOLOGY CORPORATION | WR04X5111FTL |  | G |  |  |  |  |  |  |  |
|  |  |  |  |  | 94 | 610119P00-011-G |  | RES,5.11KOhm,+/-1%,1/16W,G,SMD0402 | YAGEO CORPORATION COMPONENT | RC0402FR-075K11L |  | G |  |  |  |  |  |  |  |
|  |  |  |  |  | 94 | 610119P00-024-G |  | RES,5.11KOhm,+/-1%,1/16W,G,SMD0402 | PANASONIC INDUSTRIAL CO.,LTD. | ERJ2RKF5111X |  | G |  |  |  |  |  |  |  |
|  |  |  |  |  | 94 | 610119P00-029-G |  | RES,5.11KOhm,+/-1%,1/16W,G,SMD0402 | VISHAY ENTER TECHNO LOGY.INC | CRCW04025K11FKED |  | G |  |  |  |  |  |  |  |
|  |  |  |  | 95 | 95 | 320128V00-183-G |  | IC,Regulator,TPS73801DCQR,1A,ADJ,G,SOT223-5,SMD | TEXAS INSTRUMENTS | TPS73801DCQR | 1 | G | PLTU1 |  |  |  |  |  |  |
|  |  |  |  | 96 | 96 | 62120CM00-024-G | - | SPEA CAP,220uF,+10%~-35%,6.3V,105C,G,SMD2816,ESR<=15mOhm | PANASONIC INDUSTRIAL CO.,LTD. | EEFCX0J221YR | 2 | G | PSCCE3003,PSCCE3004 |  |  |  |  |  |  |
|  |  |  |  | 97 | 97 | 62012GF00-015-G | - | CAP,22uF,+/-20%,X6S,6.3V,G,SMD0603 | MURATA ELEC. NORTH AMERICA | GRM188C80J226M | 6 | G | PSCC2,PSCC3,PSCC3000,PSCC3010,PSCC3011,PSCC3012 |  |  |  |  |  |  |
|  |  |  |  |  | 97 | 62012GF00-023-G |  | CAP,22uF,+/-20%,X6S,6.3V,G,SMD0603 | TAIYO ELECTRIC IND.CO.LTD | JDK107BC6226MA-T |  | G |  |  |  |  |  |  |  |
|  |  |  |  | 98 | 98 | 620108000-015-G | - | CAP,100pF,+/-5%,NPO(C0G),50V,G,SMD0402 | MURATA ELEC. NORTH AMERICA | GRM1555C1H101J | 3 | G | PSCC4,PSLC14,PSGC14 |  |  |  |  |  |  |
|  |  |  |  |  | 98 | 62010800A-012-G |  | CAP,100pF,+/-5%,NPO(C0G),50V,G,SMD0402 | WALSIN TECHNOLOGY CORPORATION | 0402N101J500CT |  | G |  |  |  |  |  |  |  |
|  |  |  |  |  | 98 | 620108000-026-G |  | CAP,100pF,+/-5%,NPO(C0G),50V,G,SMD0402 | SAMSUNG SEMICONDUCTOR | CL05C101JB5NNNC |  | G |  |  |  |  |  |  |  |
|  |  |  |  |  | 98 | 620108000-023-G |  | CAP,100pF,+/-5%,NPO(C0G),50V,G,SMD0402 | TAIYO ELECTRIC IND.CO.LTD | UMK105CG101JV-F |  | G |  |  |  |  |  |  |  |
|  |  |  |  | 99 | 99 | 62013BS00-015-G |  | CAP,3nF,+/-10%,X7R,50V,G,SMD0402 | MURATA ELEC. NORTH AMERICA | GRM155R71H302KA01D | 1 | G | PSCC10 |  |  |  |  |  |  |
|  |  |  |  |  | 99 | 62013BS00-012-G |  | CAP,3nF,+/-10%,X7R,50V,G,SMD0402 | WALSIN TECHNOLOGY CORPORATION | 0402B302K500CT |  | G |  |  |  |  |  |  |  |
|  |  |  |  | 100 | 100 | 62010FF00-015-G | - | CAP,47pF,+/-5%,NPO(C0G),50V,G,SMD0402 | MURATA ELEC. NORTH AMERICA | GRM1555C1H470J | 1 | G | PSCC11 |  |  |  |  |  |  |
|  |  |  |  |  | 100 | 62010FF06-012-G |  | CAP,47pF,+/-5%,NPO(C0G),50V,G,SMD0402 | WALSIN TECHNOLOGY CORPORATION | 0402N470J500CT |  | G |  |  |  |  |  |  |  |
|  |  |  |  |  | 100 | 62010FF00-026-G |  | CAP,47pF,+/-5%,NPO(C0G),50V,G,SMD0402 | SAMSUNG SEMICONDUCTOR | CL05C470JB5NNNC |  | G |  |  |  |  |  |  |  |
|  |  |  |  |  | 100 | 62010FF00-023-G |  | CAP,47pF,+/-5%,NPO(C0G),50V,G,SMD0402 | TAIYO ELECTRIC IND.CO.LTD | UMK105CG470JV-F |  | G |  |  |  |  |  |  |  |
|  |  |  |  | 101 | 101 | 620107L00-015-G | - | CAP,2.2nF,+/-10%,X7R,50V,G,SMD0402 | MURATA ELEC. NORTH AMERICA | GRM155R71H222K | 1 | G | PSCC12 |  |  |  |  |  |  |
|  |  |  |  |  | 101 | 620107L00-012-G |  | CAP,2.2nF,+/-10%,X7R,50V,G,SMD0402 | WALSIN TECHNOLOGY CORPORATION | 0402B222K500CT |  | G |  |  |  |  |  |  |  |
|  |  |  |  |  | 101 | 620107L00-026-G |  | CAP,2.2nF,+/-10%,X7R,50V,G,SMD0402 | SAMSUNG SEMICONDUCTOR | CL05B222KB5NNNC |  | G |  |  |  |  |  |  |  |
|  |  |  |  |  | 101 | 620107L03-023-G |  | CAP,2.2nF,+/-10%,X7R,50V,G,SMD0402 | TAIYO ELECTRIC IND.CO.LTD | UMK105B7222KV-F |  | G |  |  |  |  |  |  |  |
|  |  |  |  | 102 | 102 | 62012T300-015-G | - | CAP,1uF,+/-10%,X7S,25V,G,SMD0402 | MURATA ELEC. NORTH AMERICA | GRM155C71E105KE11D | 4 | G | PSRC4,PSLC4,PSGC4,PSCC3003 |  |  |  |  |  |  |
|  |  |  |  |  | 102 | 620138700-026-G |  | CAP,1uF,+/-10%,X6S,25V,G,SMD0402 | SAMSUNG SEMICONDUCTOR | CL05X105KA5NQNC |  | G |  |  |  |  |  |  |  |
|  |  |  |  |  | 102 | 620138700-015-G |  | CAP,1uF,+/-10%,X6S,25V,G,SMD0402 | MURATA ELEC. NORTH AMERICA | GRM155C81E105KE11D |  | G |  |  |  |  |  |  |  |
|  |  |  |  | 103 | 103 | 63034FP00-088-G |  | IND,220nH@100KHz,+/-20%,23A,2.8mOhm,SHLD,G,SMD | COOPER BUSSMANN, INC. | HCM0703-R22-R | 1 | G | PSCL1 |  |  |  |  |  |  |
|  |  |  |  | 104 | 104 | 630341400-088-G | - | IND,22nH@1MHz,+/-20%,19A,368uOhm,SHLD,G,SMD | COOPER BUSSMANN, INC. | FP0404R1-R022-R | 1 | G | PSCL2 |  |  |  |  |  |  |
|  |  |  |  | 105 | 105 | 61100J300-044-G |  | RES,121Ohm,+/-0.1%,1/16W,G,SMD0402 | TA-I TECHNOLOGY CO., LTD. | RB04BTP1210 | 1 | G | PSCR5 |  |  |  |  |  |  |
|  |  |  |  | 106 | 106 | 61100U300-012-G |  | RES,210 Ohm,+/-0.1%,1/16W,G,SMD0402 | WALSIN TECHNOLOGY CORPORATION | WF04U2100BTL | 1 | G | PSCR6 |  |  |  |  |  |  |
|  |  |  |  | 107 | 107 | 61011C400-017-G | - | RES,4.32KOhm,+/-1%,1/16W,G,SMD0402 | KOA SPEER ELECTRONICS, INC. | RK73H1ETTP4321F | 1 | G | PSCR10 |  |  |  |  |  |  |
|  |  |  |  |  | 107 | 61011C400-012-G |  | RES,4.32KOhm,+/-1%,1/16W,G,SMD0402 | WALSIN TECHNOLOGY CORPORATION | WR04X4321FTL |  | G |  |  |  |  |  |  |  |
|  |  |  |  |  | 107 | 61011C400-011-G |  | RES,4.32KOhm,+/-1%,1/16W,G,SMD0402 | YAGEO CORPORATION COMPONENT | RC0402FR-074K32L |  | G |  |  |  |  |  |  |  |
|  |  |  |  |  | 107 | 61011C400-044-G |  | RES,4.32KOhm,+/-1%,1/16W,G,SMD0402 | TA-I TECHNOLOGY CO., LTD. | RM04FTN4321 |  | G |  |  |  |  |  |  |  |
|  |  |  |  | 108 | 108 | 610112J00-017-G | - | RES,200 Ohm,+/-1%,1/16W,G,SMD0402 | KOA SPEER ELECTRONICS, INC. | RK73H1ETTP2000F | 1 | G | PSCR11 |  |  |  |  |  |  |
|  |  |  |  |  | 108 | 610112J00-012-G |  | RES,200 Ohm,+/-1%,1/16W,G,SMD0402 | WALSIN TECHNOLOGY CORPORATION | WR04X2000FTL |  | G |  |  |  |  |  |  |  |
|  |  |  |  |  | 108 | 610112J00-011-G |  | RES,200 Ohm,+/-1%,1/16W,G,SMD0402 | YAGEO CORPORATION COMPONENT | RC0402FR-07200RL |  | G |  |  |  |  |  |  |  |
|  |  |  |  |  | 108 | 610112J00-044-G |  | RES,200 Ohm,+/-1%,1/16W,G,SMD0402 | TA-I TECHNOLOGY CO., LTD. | RM04FTN2000 |  | G |  |  |  |  |  |  |  |
|  |  |  |  |  | 108 | 610112J00-029-G |  | RES,200 Ohm,+/-1%,1/16W,G,SMD0402 | VISHAY ENTER TECHNO LOGY.INC | CRCW0402200RFKED |  | G |  |  |  |  |  |  |  |
|  |  |  |  |  | 108 | 610112J00-024-G |  | RES,200 Ohm,+/-1%,1/16W,G,SMD0402 | PANASONIC INDUSTRIAL CO.,LTD. | ERJ2RKF2000X |  | G |  |  |  |  |  |  |  |
|  |  |  |  | 109 | 109 | 61011JY00-017-G | - | RES,39.2KOhm,+/-1%,1/16W,G,SMD0402 | KOA SPEER ELECTRONICS, INC. | RK73H1ETTP3922F | 1 | G | PSCR15 |  |  |  |  |  |  |
|  |  |  |  |  | 109 | 61011JY00-012-G |  | RES,39.2KOhm,+/-1%,1/16W,G,SMD0402 | WALSIN TECHNOLOGY CORPORATION | WR04X3922FTL |  | G |  |  |  |  |  |  |  |
|  |  |  |  |  | 109 | 61011JY00-011-G |  | RES,39.2KOhm,+/-1%,1/16W,G,SMD0402 | YAGEO CORPORATION COMPONENT | RC0402FR-0739K2L |  | G |  |  |  |  |  |  |  |
|  |  |  |  |  | 109 | 61011JY00-044-G |  | RES,39.2KOhm,+/-1%,1/16W,G,SMD0402 | TA-I TECHNOLOGY CO., LTD. | RM04FTN3922 |  | G |  |  |  |  |  |  |  |
|  |  |  |  |  | 109 | 61011JY00-029-G |  | RES,39.2KOhm,+/-1%,1/16W,G,SMD0402 | VISHAY ENTER TECHNO LOGY.INC | CRCW040239K2FKED |  | G |  |  |  |  |  |  |  |
|  |  |  |  | 110 | 110 | 61011RF00-017-G |  | RES,1.8KOhm,+/-1%,1/8W,G,SMD0805 | KOA SPEER ELECTRONICS, INC. | RK73H2ATTD1801F | 2 | G | PSGR20,PSCR3000 |  |  |  |  |  |  |
|  |  |  |  |  | 110 | 61011RF00-011-G |  | RES,1.8KOhm,+/-1%,1/8W,G,SMD0805 | YAGEO CORPORATION COMPONENT | RC0805FR-071K8L |  | G |  |  |  |  |  |  |  |
|  |  |  |  |  | 110 | 61011RF00-012-G |  | RES,1.8KOhm,+/-1%,1/8W,G,SMD0805 | WALSIN TECHNOLOGY CORPORATION | WR08X1801FTL |  | G |  |  |  |  |  |  |  |
|  |  |  |  | 111 | 111 | 32013HH00-238-G |  | IC,Regulator,IR3447MTRPBF,ADJ,25A,G,PQFN-33 | INTERNATIONAL RECTIFIER | IR3447MTRPBF | 1 | G | PSCU1 |  |  |  |  |  |  |
|  |  |  |  | 112 | 112 | 62012CM01-015-G |  | CAP,10uF,+/-20%,X6S,4V,G,SMD0603 | MURATA ELEC. NORTH AMERICA | GRM188C80G106M | 2 | G | PSLC16,PSGC16 |  |  |  |  |  |  |
|  |  |  |  |  | 112 | 62012CM00-023-G |  | CAP,10uF,+/-20%,X6S,4V,G,SMD0603 | TAIYO ELECTRIC IND.CO.LTD | AMK107AC6106MA-T |  | G |  |  |  |  |  |  |  |
|  |  |  |  |  | 112 | 62012CM00-026-G |  | CAP,10uF,+/-20%,X6S,4V,G,SMD0603 | SAMSUNG SEMICONDUCTOR | CL10X106MR8NNNC |  | G |  |  |  |  |  |  |  |
|  |  |  |  | 113 | 113 | 63033JK00-15A-G |  | IND,2.2uH@100KHz,+/-20%,9A,16.5mOhm,SHLD,G,SMD | The Inter-Technical Group, Inc. | SMHC2511A-2R2MHF | 1 | G | PSGL2 |  |  |  |  |  |  |
|  |  |  |  | 114 | 114 | 61010G500-017-G | - | RES,10KOhm,+/-1%,1/16W,G,SMD0402 | KOA SPEER ELECTRONICS, INC. | RK73H1ETTP1002F | 62 | G | PSRR6,PSLR6,PSGR6,R18,R40,R41,R42,R43,R44,R45,R46,R89,R90,R91,R102,R103,R104,R127,R128,R129,R130,R134,R139,R141,R234,R248,R342,R343,R344,R345,R346,R347,R348,R349,R350,R351,R352,R353,R354,R355,R356,R357,R358,R359,R360,R361,R371,R397,R398,R404,R405,R406,R407,R442,R443,R1487,R1493,R1497,R1501,R1511,R1512,R1544, |  |  |  |  |  |  |
|  |  |  |  |  | 114 | 61010G500-012-G |  | RES,10KOhm,+/-1%,1/16W,G,SMD0402 | WALSIN TECHNOLOGY CORPORATION | WR04X1002FTL |  | G |  |  |  |  |  |  |  |
|  |  |  |  |  | 114 | 61010G500-011-G |  | RES,10KOhm,+/-1%,1/16W,G,SMD0402 | YAGEO CORPORATION COMPONENT | RC0402FR-0710KL |  | G |  |  |  |  |  |  |  |
|  |  |  |  |  | 114 | 61010G500-044-G |  | RES,10KOhm,+/-1%,1/16W,G,SMD0402 | TA-I TECHNOLOGY CO., LTD. | RM04FTN1002 |  | G |  |  |  |  |  |  |  |
|  |  |  |  |  | 114 | 61010G500-029-G |  | RES,10KOhm,+/-1%,1/16W,G,SMD0402 | VISHAY ENTER TECHNO LOGY.INC | CRCW040210K0FKED |  | G |  |  |  |  |  |  |  |
|  |  |  |  |  | 114 | 61010G500-024-G |  | RES,10KOhm,+/-1%,1/16W,G,SMD0402 | PANASONIC INDUSTRIAL CO.,LTD. | ERJ2RKF1002X |  | G |  |  |  |  |  |  |  |
|  |  |  |  | 115 | 115 | 61100QY00-044-G |  | RES,17.4KOhm,+/-0.1%,1/16W,G,SMD0402 | TA-I TECHNOLOGY CO., LTD. | RB04BTP1742 | 1 | G | PSGR17 |  |  |  |  |  |  |
|  |  |  |  | 116 | 116 | 61100PL00-044-G |  | RES,10.2KOhm,+/-0.1%,1/16W,G,SMD0402 | TA-I TECHNOLOGY CO., LTD. | RB04BTP1022 | 1 | G | PSGR19 |  |  |  |  |  |  |
|  |  |  |  | 117 | 117 | 32013PD00-238-G |  | IC,Regulator,IR3883MTRPbF,ADJ,3A,G,QFN-16,SMD | INTERNATIONAL RECTIFIER | IR3883MTRPBF | 3 | G | PSRU1,PSLU1,PSGU1 |  |  |  |  |  |  |
|  |  |  |  | 118 | 118 | 630328U00-088-G |  | IND,3.3uH@100KHz,+/-20%,6A,30mOhm,SHLD,G,SMD | COOPER BUSSMANN, INC. | HCM0703-3R3-R | 1 | G | PSLL2 |  |  |  |  |  |  |
|  |  |  |  | 119 | 119 | 61100DF00-044-G |  | RES,6.34KOhm,+/-0.1%,1/16W,G,SMD0402 | TA-I TECHNOLOGY CO., LTD. | RB04BTP6341 | 1 | G | PSLR19 |  |  |  |  |  |  |
|  |  |  |  | 120 | 120 | 620105U00-015-G | - | CAP,220pF,+/-10%,X7R,50V,G,SMD0402 | MURATA ELEC. NORTH AMERICA | GRM155R71H221K | 1 | G | PSRC14 |  |  |  |  |  |  |
|  |  |  |  |  | 120 | 620105U00-012-G |  | CAP,220pF,+/-10%,X7R,50V,G,SMD0402 | WALSIN TECHNOLOGY CORPORATION | 0402B221K500CT |  | G |  |  |  |  |  |  |  |
|  |  |  |  |  | 120 | 620105U00-026-G |  | CAP,220pF,+/-10%,X7R,50V,G,SMD0402 | SAMSUNG SEMICONDUCTOR | CL05B221KB5NNNC |  | G |  |  |  |  |  |  |  |
|  |  |  |  | 121 | 121 | 63031AD04-129-G |  | IND,4.7uH@100KHz,+/-20%,5.5A,40mOhm,SHLD,G,SMD | MAG.LAYERS, SCIENTIFIC-TECHNICS (KUNSHAN) CO., LTD. | SPS-06CZ-4R7M-V1 | 1 | G | PSRL2 |  |  |  |  |  |  |
|  |  |  |  | 122 | 122 | 610117D00-017-G | - | RES,13.3KOhm,+/-1%,1/16W,G,SMD0402 | KOA SPEER ELECTRONICS, INC. | RK73H1ETTP1332F | 1 | G | PSRR1 |  |  |  |  |  |  |
|  |  |  |  |  | 122 | 610117D00-012-G |  | RES,13.3KOhm,+/-1%,1/16W,G,SMD0402 | WALSIN TECHNOLOGY CORPORATION | WR04X1332FTL |  | G |  |  |  |  |  |  |  |
|  |  |  |  |  | 122 | 610117D00-011-G |  | RES,13.3KOhm,+/-1%,1/16W,G,SMD0402 | YAGEO CORPORATION COMPONENT | RC0402FR-0713K3L |  | G |  |  |  |  |  |  |  |
|  |  |  |  |  | 122 | 610117D00-044-G |  | RES,13.3KOhm,+/-1%,1/16W,G,SMD0402 | TA-I TECHNOLOGY CO., LTD. | RM04FTN1332 |  | G |  |  |  |  |  |  |  |
|  |  |  |  | 123 | 123 | 61100YB00-044-G |  | RES,2.94KOhm,+/-0.1%,1/16W,G,SMD0402 | TA-I TECHNOLOGY CO., LTD | RB04BTP2941 | 1 | G | PSRR19 |  |  |  |  |  |  |
|  |  |  |  | 124 | 124 | 51050KW00-131-G |  | MOS N/N,SSM6N36FE,20V,500mA,0.63@5V,G,ES6-6,SMD | TOSHIBA ELECTRONICS ASIA LTD | SSM6N36FE | 4 | G | QN1,QN2,QN3,QN5 |  |  |  |  |  |  |
|  |  |  |  | 125 | 125 | 510329S00-131-G |  | MOS N,SSM6N7002KFU,LF(T,60V,300mA,1.5@10V,G,US6-6,SMD | TOSHIBA ELECTRONICS ASIA LTD | SSM6N7002KFU,LF(T | 1 | G | QN4 |  |  |  |  |  |  |
|  |  |  |  | 126 | 126 | 510301D00-223-G |  | MOS N,BSS138LT1G,50V,0.2A,3.5ohm@5V,G,SOT23-3,SMD | ON SEMICONDUCTOR CORP | BSS138LT1G | 5 | G | Q1,Q2,Q3,Q8,Q9 |  |  |  |  |  |  |
|  |  |  |  | 127 | 127 | 51040MH00-221-G |  | MOS P,BSC030P03NS3 G,30V,100A,4.6m@6V,G,TDSON-8,SMD | INFINEON TECHNOLOGIES CORP. | BSC030P03NS3 G | 2 | G | Q4,Q6 |  |  |  |  |  |  |
|  |  |  |  | 128 | 128 | 51030SM00-029-G |  | MOSFET-N,SIS412DN-T1-GE3,30V,12A,24mOhm@Vgs=10V,30mOhm@Vgs=4.5V,PowerPAK1212,8P,G | VISHAY ENTER TECHNO LOGY.INC | SIS412DN-T1-GE3 | 1 | G | Q5 |  |  |  |  |  |  |
|  |  |  |  | 129 | 129 | 51030CQ00-185-G |  | MOS N,2N7002,60V,115mA,7.5ohm@5V,G,SOT23-3,SMD | FAIRCHILD SEMICONDUCTOR CORP | 2N7002 | 1 | G | Q7 |  |  |  |  |  |  |
|  |  |  |  | 130 | 130 | 61010H800-017-G |  | RES,5.11 Ohm,+/-1%,1/10W,G,SMD0603 | KOA SPEER ELECTRONICS, INC. | RK73H1JTTD5R11F | 1 | G | R4 |  |  |  |  |  |  |
|  |  |  |  |  | 130 | 61010H800-012-G |  | RES,5.11 Ohm,+/-1%,1/10W,G,SMD0603 | WALSIN TECHNOLOGY CORPORATION | WR06W5R11FTL |  | G |  |  |  |  |  |  |  |
|  |  |  |  |  | 130 | 61010H800-011-G |  | RES,5.11 Ohm,+/-1%,1/10W,G,SMD0603 | YAGEO CORPORATION COMPONENT | RC0603FR-075R11L |  | G |  |  |  |  |  |  |  |
|  |  |  |  |  | 130 | 61010H800-044-G |  | RES,5.11 Ohm,+/-1%,1/10W,G,SMD0603 | TA-I TECHNOLOGY CO., LTD. | RM06FTN5R11 |  | G |  |  |  |  |  |  |  |
|  |  |  |  | 131 | 131 | 61011MQ00-017-G | - | RES,4.75KOhm,+/-1%,1/16W,G,SMD0402 | KOA SPEER ELECTRONICS, INC. | RK73H1ETTP4751F | 15 | G | R5,R28,R30,R34,R36,R78,R84,R92,R188,R195,R210,R211,R241,R242,R1446 |  |  |  |  |  |  |
|  |  |  |  |  | 131 | 61011MQ00-011-G |  | RES,4.75KOhm,+/-1%,1/16W,G,SMD0402 | YAGEO CORPORATION COMPONENT | RC0402FR-074K75L |  | G |  |  |  |  |  |  |  |
|  |  |  |  |  | 131 | 61011MQ00-012-G |  | RES,4.75KOhm,+/-1%,1/16W,G,SMD0402 | WALSIN TECHNOLOGY CORPORATION | WR04X4751FTL |  | G |  |  |  |  |  |  |  |
|  |  |  |  |  | 131 | 61011MQ00-044-G |  | RES,4.75KOhm,+/-1%,1/16W,G,SMD0402 | TA-I TECHNOLOGY CO., LTD. | RM04FTN4751 |  | G |  |  |  |  |  |  |  |
|  |  |  |  | 132 | 132 | 61011KB00-017-G | - | RES,51.1 Ohm,+/-1%,1/16W,G,SMD0402 | KOA SPEER ELECTRONICS, INC. | RK73H1ETTP51R1F | 4 | G | R6,R8,R9,R10 |  |  |  |  |  |  |
|  |  |  |  |  | 132 | 61011KB00-011-G |  | RES,51.1 Ohm,+/-1%,1/16W,G,SMD0402 | YAGEO CORPORATION COMPONENT | RC0402FR-0751R1L |  | G |  |  |  |  |  |  |  |
|  |  |  |  |  | 132 | 61011KB00-012-G |  | RES,51.1 Ohm,+/-1%,1/16W,G,SMD0402 | WALSIN TECHNOLOGY CORPORATION | WR04X51R1FTL |  | G |  |  |  |  |  |  |  |
|  |  |  |  |  | 132 | 61011KB00-044-G |  | RES,51.1 Ohm,+/-1%,1/16W,G,SMD0402 | TA-I TECHNOLOGY CO., LTD. | RM04FTN51R1 |  | G |  |  |  |  |  |  |  |
|  |  |  |  | 133 | 133 | 61011BH00-017-G |  | RES,22.1 Ohm,+/-1%,1/16W,G,SMD0402 | KOA SPEER ELECTRONICS, INC. | RK73H1ETTP22R1F | 3 | G | R12,R13,R136 |  |  |  |  |  |  |
|  |  |  |  |  | 133 | 61011BH00-012-G |  | RES,22.1 Ohm,+/-1%,1/16W,G,SMD0402 | WALSIN TECHNOLOGY CORPORATION | WR04X22R1FTL |  | G |  |  |  |  |  |  |  |
|  |  |  |  |  | 133 | 61011BH00-011-G |  | RES,22.1 Ohm,+/-1%,1/16W,G,SMD0402 | YAGEO CORPORATION COMPONENT | RC0402FR-0722R1L |  | G |  |  |  |  |  |  |  |
|  |  |  |  |  | 133 | 61011BH00-044-G |  | RES,22.1 Ohm,+/-1%,1/16W,G,SMD0402 | TA-I TECHNOLOGY CO., LTD. | RM04FTN22R1 |  | G |  |  |  |  |  |  |  |
|  |  |  |  | 134 | 134 | 61011M600-017-G |  | RES,82.5 Ohm,+/-1%,1/16W,G,SMD0402 | KOA SPEER ELECTRONICS, INC. | RK73H1ETTP82R5F | 1 | G | R14 |  |  |  |  |  |  |
|  |  |  |  |  | 134 | 61011M600-011-G |  | RES,82.5 Ohm,+/-1%,1/16W,G,SMD0402 | YAGEO CORPORATION COMPONENT | RC0402FR-0782R5L |  | G |  |  |  |  |  |  |  |
|  |  |  |  |  | 134 | 61011M600-012-G |  | RES,82.5 Ohm,+/-1%,1/16W,G,SMD0402 | WALSIN TECHNOLOGY CORPORATION | WR04X82R5FTL |  | G |  |  |  |  |  |  |  |
|  |  |  |  | 135 | 135 | 610112W00-017-G |  | RES,2KOhm,+/-5%,1/16W,G,SMD0402 | KOA SPEER ELECTRONICS, INC. | RK73B1ETTP202J | 37 | G | R15,R17,R27,R29,R38,R39,R48,R49,R50,R51,R53,R54,R55,R57,R58,R59,R60,R61,R62,R63,R64,R65,R66,R67,R68,R69,R79,R80,R81,R82,R83,R87,R93,R95,R97,R98,R99 |  |  |  |  |  |  |
|  |  |  |  |  | 135 | 610112W00-012-G |  | RES,2KOhm,+/-5%,1/16W,G,SMD0402 | WALSIN TECHNOLOGY CORPORATION | WR04X202JTL |  | G |  |  |  |  |  |  |  |
|  |  |  |  |  | 135 | 610112W00-011-G |  | RES,2KOhm,+/-5%,1/16W,G,SMD0402 | YAGEO CORPORATION COMPONENT | RC0402JR-072KL |  | G |  |  |  |  |  |  |  |
|  |  |  |  |  | 135 | 610112W00-044-G |  | RES,2KOhm,+/-5%,1/16W,G,SMD0402 | TA-I TECHNOLOGY CO., LTD. | RM04JTN202 |  | G |  |  |  |  |  |  |  |
|  |  |  |  |  | 135 | 610112W00-024-G |  | RES,2KOhm,+/-5%,1/16W,G,SMD0402 | PANASONIC INDUSTRIAL CO.,LTD. | ERJ2GEJ202X |  | G |  |  |  |  |  |  |  |
|  |  |  |  | 136 | 136 | 610114E00-017-G |  | RES,33.2 Ohm,+/-1%,1/16W,G,SMD0402 | KOA SPEER ELECTRONICS, INC. | RK73H1ETTP33R2F | 1 | G | R16 |  |  |  |  |  |  |
|  |  |  |  |  | 136 | 610114E00-012-G |  | RES,33.2 Ohm,+/-1%,1/16W,G,SMD0402 | WALSIN TECHNOLOGY CORPORATION | WR04X33R2FTL |  | G |  |  |  |  |  |  |  |
|  |  |  |  |  | 136 | 610114E00-011-G |  | RES,33.2 Ohm,+/-1%,1/16W,G,SMD0402 | YAGEO CORPORATION COMPONENT | RC0402FR-0733R2L |  | G |  |  |  |  |  |  |  |
|  |  |  |  |  | 136 | 610114E00-044-G |  | RES,33.2 Ohm,+/-1%,1/16W,G,SMD0402 | TA-I TECHNOLOGY CO., LTD. | RM04FTN33R2 |  | G |  |  |  |  |  |  |  |
|  |  |  |  | 137 | 137 | 610114J00-017-G | - | RES,2KOhm,+/-1%,1/16W,G,SMD0402 | KOA SPEER ELECTRONICS, INC. | RK73H1ETTP2001F | 1 | G | R26 |  |  |  |  |  |  |
|  |  |  |  |  | 137 | 610114J00-012-G |  | RES,2KOhm,+/-1%,1/16W,G,SMD0402 | WALSIN TECHNOLOGY CORPORATION | WR04X2001FTL |  | G |  |  |  |  |  |  |  |
|  |  |  |  |  | 137 | 610114J00-011-G |  | RES,2KOhm,+/-1%,1/16W,G,SMD0402 | YAGEO CORPORATION COMPONENT | RC0402FR-072KL |  | G |  |  |  |  |  |  |  |
|  |  |  |  |  | 137 | 610114J00-044-G |  | RES,2KOhm,+/-1%,1/16W,G,SMD0402 | TA-I TECHNOLOGY CO., LTD. | RM04FTN2001 |  | G |  |  |  |  |  |  |  |
|  |  |  |  |  | 137 | 610114J00-024-G |  | RES,2KOhm,+/-1%,1/16W,G,SMD0402 | PANASONIC INDUSTRIAL CO.,LTD. | ERJ2RKF2001X |  | G |  |  |  |  |  |  |  |
|  |  |  |  |  | 137 | 610114J00-029-G |  | RES,2KOhm,+/-1%,1/16W,G,SMD0402 | VISHAY ENTER TECHNO LOGY.INC | CRCW04022K00FKED |  | G |  |  |  |  |  |  |  |
|  |  |  |  | 138 | 138 | 61010JY00-017-G | - | RES,220 Ohm,+/-5%,1/16W,G,SMD0402 | KOA SPEER ELECTRONICS, INC. | RK73B1ETTP221J | 5 | G | R192,R194,R200,R201,R203 |  |  |  |  |  |  |
|  |  |  |  |  | 138 | 61010JY00-012-G |  | RES,220 Ohm,+/-5%,1/16W,G,SMD0402 | WALSIN TECHNOLOGY CORPORATION | WR04X221JTL |  | G |  |  |  |  |  |  |  |
|  |  |  |  |  | 138 | 61010JY00-011-G |  | RES,220 Ohm,+/-5%,1/16W,G,SMD0402 | YAGEO CORPORATION COMPONENT | RC0402JR-07220RL |  | G |  |  |  |  |  |  |  |
|  |  |  |  |  | 138 | 61010JY00-044-G |  | RES,220 Ohm,+/-5%,1/16W,G,SMD0402 | TA-I TECHNOLOGY CO., LTD. | RM04JTN221 |  | G |  |  |  |  |  |  |  |
|  |  |  |  | 139 | 139 | 61012RW00-017-G |  | RES,510mOhm,+/-1%,1/8W,G,SMD0402 | KOA SPEER ELECTRONICS, INC. | SR731ETTPR510F | 12 | G | R115,R116,R117,R118,R119,R120,R121,R122,R123,R124,R125,R126 |  |  |  |  |  |  |
|  |  |  |  |  | 139 | 61012RW00-011-G |  | RES,510mOhm,+/-1%,1/8W,G,SMD0402 | YAGEO CORPORATION COMPONENT | PT0402FR-7W0R51L |  | G |  |  |  |  |  |  |  |
|  |  |  |  |  | 139 | 61012RW00-012-G |  | RES,510mOhm,+/-1%,1/8W,G,SMD0402 | WALSIN TECHNOLOGY CORPORATION | WW04PR510FTL |  | G |  |  |  |  |  |  |  |
|  |  |  |  | 140 | 140 | 61011T000-017-G |  | RES,82 Ohm,+/-1%,1/16W,G,SMD0402 | KOA SPEER ELECTRONICS, INC. | RK73H1ETTP82R0F | 42 | G | R143,R144,R145,R146,R147,R148,R149,R150,R151,R152,R153,R154,R155,R156,R157,R158,R159,R160,R161,R162,R163,R164,R165,R166,R167,R168,R169,R170,R171,R172,R173,R174,R175,R177,R178,R179,R180,R181,R182,R183,R184,R185 |  |  |  |  |  |  |
|  |  |  |  |  | 140 | 61011T000-011-G |  | RES,82 Ohm,+/-1%,1/16W,G,SMD0402 | YAGEO CORPORATION COMPONENT | RC0402FR-0782RL |  | G |  |  |  |  |  |  |  |
|  |  |  |  |  | 140 | 61011T000-012-G |  | RES,82 Ohm,+/-1%,1/16W,G,SMD0402 | WALSIN TECHNOLOGY CORPORATION | WR04X82R0FTL |  | G |  |  |  |  |  |  |  |
|  |  |  |  |  | 140 | 61011T000-044-G |  | RES,82 Ohm,+/-1%,1/16W,G,SMD0402 | TA-I TECHNOLOGY CO., LTD. | RM04FTN82R0 |  | G |  |  |  |  |  |  |  |
|  |  |  |  | 141 | 141 | 610101V00-017-G | K9572 | RES,22 Ohm,+/-5%,1/16W,G,SMD0402 | KOA SPEER ELECTRONICS, INC. | RK73B1ETTP220J | 1 | G | R190 |  |  |  |  |  |  |
|  |  |  |  |  | 141 | 610101V00-012-G |  | RES,22 Ohm,+/-5%,1/16W,G,SMD0402 | WALSIN TECHNOLOGY CORPORATION | WR04X220JTL |  | G |  |  |  |  |  |  |  |
|  |  |  |  |  | 141 | 610101V00-011-G |  | RES,22 Ohm,+/-5%,1/16W,G,SMD0402 | YAGEO CORPORATION COMPONENT | RC0402JR-0722RL |  | G |  |  |  |  |  |  |  |
|  |  |  |  |  | 141 | 610101V00-044-G |  | RES,22 Ohm,+/-5%,1/16W,G,SMD0402 | TA-I TECHNOLOGY CO., LTD. | RM04JTN220 |  | G |  |  |  |  |  |  |  |
|  |  |  |  |  | 141 | 610101V00-024-G |  | RES,22 Ohm,+/-5%,1/16W,G,SMD0402 | PANASONIC INDUSTRIAL CO.,LTD. | ERJ2GEJ220X |  | G |  |  |  |  |  |  |  |
|  |  |  |  | 142 | 142 | 61011H500-017-G | - | RES,22 Ohm,+/-1%,1/16W,G,SMD0402 | KOA SPEER ELECTRONICS, INC. | RK73H1ETTP22R0F | 1 | G | R202 |  |  |  |  |  |  |
|  |  |  |  |  | 142 | 61011H500-012-G |  | RES,22 Ohm,+/-1%,1/16W,G,SMD0402 | WALSIN TECHNOLOGY CORPORATION | WR04X22R0FTL |  | G |  |  |  |  |  |  |  |
|  |  |  |  |  | 142 | 61011H500-011-G |  | RES,22 Ohm,+/-1%,1/16W,G,SMD0402 | YAGEO CORPORATION COMPONENT | RC0402FR-0722RL |  | G |  |  |  |  |  |  |  |
|  |  |  |  |  | 142 | 61011H500-044-G |  | RES,22 Ohm,+/-1%,1/16W,G,SMD0402 | TA-I TECHNOLOGY CO., LTD. | RM04FTN22R0 |  | G |  |  |  |  |  |  |  |
|  |  |  |  |  | 142 | 61011H500-024-G |  | RES,22 Ohm,+/-1%,1/16W,G,SMD0402 | PANASONIC INDUSTRIAL CO.,LTD. | ERJ2RKF22R0X |  | G |  |  |  |  |  |  |  |
|  |  |  |  | 143 | 143 | 610100T00-017-G |  | RES,1KOhm,+/-5%,1/16W,G,SMD0402 | KOA SPEER ELECTRONICS, INC. | RK73B1ETTP102J | 7 | G | R208,R209,R218,R219,R224,R225,R1510 |  |  |  |  |  |  |
|  |  |  |  |  | 143 | 610100T00-012-G |  | RES,1KOhm,+/-5%,1/16W,G,SMD0402 | WALSIN TECHNOLOGY CORPORATION | WR04X102JTL |  | G |  |  |  |  |  |  |  |
|  |  |  |  |  | 143 | 610100T00-011-G |  | RES,1KOhm,+/-5%,1/16W,G,SMD0402 | YAGEO CORPORATION COMPONENT | RC0402JR-071KL |  | G |  |  |  |  |  |  |  |
|  |  |  |  |  | 143 | 610100T00-044-G |  | RES,1KOhm,+/-5%,1/16W,G,SMD0402 | TA-I TECHNOLOGY CO., LTD. | RM04JTN102 |  | G |  |  |  |  |  |  |  |
|  |  |  |  |  | 143 | 610100T00-024-G |  | RES,1KOhm,+/-5%,1/16W,G,SMD0402 | PANASONIC INDUSTRIAL CO.,LTD. | ERJ2GEJ102X |  | G |  |  |  |  |  |  |  |
|  |  |  |  | 144 | 144 | 610107B00-017-G | K9576 | RES,4.7KOhm,+/-5%,1/16W,G,SMD0402 | KOA SPEER ELECTRONICS, INC. | RK73B1ETTP472J | 4 | G | R228,R1415,R1440,R1517 |  |  |  |  |  |  |
|  |  |  |  |  | 144 | 610107B00-012-G |  | RES,4.7KOhm,+/-5%,1/16W,G,SMD0402 | WALSIN TECHNOLOGY CORPORATION | WR04X472JTL |  | G |  |  |  |  |  |  |  |
|  |  |  |  |  | 144 | 610107B00-011-G |  | RES,4.7KOhm,+/-5%,1/16W,G,SMD0402 | YAGEO CORPORATION COMPONENT | RC0402JR-074K7L |  | G |  |  |  |  |  |  |  |
|  |  |  |  |  | 144 | 610107B00-044-G |  | RES,4.7KOhm,+/-5%,1/16W,G,SMD0402 | TA-I TECHNOLOGY CO., LTD. | RM04JTN472 |  | G |  |  |  |  |  |  |  |
|  |  |  |  |  | 144 | 610107B00-024-G |  | RES,4.7KOhm,+/-5%,1/16W,G,SMD0402 | PANASONIC INDUSTRIAL CO.,LTD. | ERJ2GEJ472X |  | G |  |  |  |  |  |  |  |
|  |  |  |  |  | 144 | 610107B00-029-G |  | RES,4.7KOhm,+/-5%,1/16W,G,SMD0402 | VISHAY ENTER TECHNO LOGY.INC | CRCW04024K70JNED |  | G |  |  |  |  |  |  |  |
|  |  |  |  | 145 | 145 | 61010L100-017-G | - | RES,100KOhm,+/-1%,1/16W,G,SMD0402 | KOA SPEER ELECTRONICS, INC. | RK73H1ETTP1003F | 3 | G | R233,R238,R245 |  |  |  |  |  |  |
|  |  |  |  |  | 145 | 61010L100-012-G |  | RES,100KOhm,+/-1%,1/16W,G,SMD0402 | WALSIN TECHNOLOGY CORPORATION | WR04X1003FTL |  | G |  |  |  |  |  |  |  |
|  |  |  |  |  | 145 | 61010L100-011-G |  | RES,100KOhm,+/-1%,1/16W,G,SMD0402 | YAGEO CORPORATION COMPONENT | RC0402FR-07100KL |  | G |  |  |  |  |  |  |  |
|  |  |  |  |  | 145 | 61010L100-044-G |  | RES,100KOhm,+/-1%,1/16W,G,SMD0402 | TA-I TECHNOLOGY CO., LTD. | RM04FTN1003 |  | G |  |  |  |  |  |  |  |
|  |  |  |  |  | 145 | 61010L106-029-G |  | RES,100KOhm,+/-1%,1/16W,G,SMD0402 | VISHAY ENTER TECHNO LOGY.INC | CRCW0402100KFKEDC |  | G |  |  |  |  |  |  |  |
|  |  |  |  |  | 145 | 61010L100-024-G |  | RES,100KOhm,+/-1%,1/16W,G,SMD0402 | PANASONIC INDUSTRIAL CO.,LTD. | ERJ2RKF1003X |  | G |  |  |  |  |  |  |  |
|  |  |  |  | 146 | 146 | 61011WQ00-017-G | - | RES,3KOhm,+/-1%,1/16W,G,SMD0402 | KOA SPEER ELECTRONICS, INC. | RK73H1ETTP3001F | 56 | G | R255,R256,R257,R258,R259,R260,R261,R262,R263,R268,R269,R270,R271,R272,R273,R274,R275,R276,R281,R282,R283,R284,R285,R286,R287,R288,R289,R297,R298,R299,R300,R301,R302,R303,R304,R305,R310,R311,R312,R313,R314,R315,R316,R317,R318,R326,R327,R328,R329,R330,R331,R332,R333,R334,R383,R384 |  |  |  |  |  |  |
|  |  |  |  |  | 146 | 61011WQ00-012-G |  | RES,3KOhm,+/-1%,1/16W,G,SMD0402 | WALSIN TECHNOLOGY CORPORATION | WR04X3001FTL |  | G |  |  |  |  |  |  |  |
|  |  |  |  |  | 146 | 61011WQ00-011-G |  | RES,3KOhm,+/-1%,1/16W,G,SMD0402 | YAGEO CORPORATION COMPONENT | RC0402FR-073KL |  | G |  |  |  |  |  |  |  |
|  |  |  |  |  | 146 | 61011WQ00-044-G |  | RES,3KOhm,+/-1%,1/16W,G,SMD0402 | TA-I TECHNOLOGY CO., LTD. | RM04FTN3001 |  | G |  |  |  |  |  |  |  |
|  |  |  |  | 147 | 147 | 61011B000-017-G | - | RES,1.5KOhm,+/-1%,1/16W,G,SMD0402 | KOA SPEER ELECTRONICS, INC. | RK73H1ETTP1501F | 1 | G | R382 |  |  |  |  |  |  |
|  |  |  |  |  | 147 | 61011B000-012-G |  | RES,1.5KOhm,+/-1%,1/16W,G,SMD0402 | WALSIN TECHNOLOGY CORPORATION | WR04X1501FTL |  | G |  |  |  |  |  |  |  |
|  |  |  |  |  | 147 | 61011B000-011-G |  | RES,1.5KOhm,+/-1%,1/16W,G,SMD0402 | YAGEO CORPORATION COMPONENT | RC0402FR-071K5L |  | G |  |  |  |  |  |  |  |
|  |  |  |  |  | 147 | 61011B000-044-G |  | RES,1.5KOhm,+/-1%,1/16W,G,SMD0402 | TA-I TECHNOLOGY CO., LTD. | RM04FTN1501 |  | G |  |  |  |  |  |  |  |
|  |  |  |  |  | 147 | 61011B000-024-G |  | RES,1.5KOhm,+/-1%,1/16W,G,SMD0402 | PANASONIC INDUSTRIAL CO.,LTD. | ERJ2RKF1501X |  | G |  |  |  |  |  |  |  |
|  |  |  |  | 148 | 148 | 610102700-017-G | - | RES,49.9 Ohm,+/-1%,1/16W,G,SMD0402 | KOA SPEER ELECTRONICS, INC. | RK73H1ETTP49R9F | 2 | G | R445,R448 |  |  |  |  |  |  |
|  |  |  |  |  | 148 | 610102700-012-G |  | RES,49.9 Ohm,+/-1%,1/16W,G,SMD0402 | WALSIN TECHNOLOGY CORPORATION | WR04X49R9FTL |  | G |  |  |  |  |  |  |  |
|  |  |  |  |  | 148 | 610102700-011-G |  | RES,49.9 Ohm,+/-1%,1/16W,G,SMD0402 | YAGEO CORPORATION COMPONENT | RC0402FR-0749R9L |  | G |  |  |  |  |  |  |  |
|  |  |  |  |  | 148 | 610102700-044-G |  | RES,49.9 Ohm,+/-1%,1/16W,G,SMD0402 | TA-I TECHNOLOGY CO., LTD. | RM04FTN49R9 |  | G |  |  |  |  |  |  |  |
|  |  |  |  |  | 148 | 610102700-029-G |  | RES,49.9 Ohm,+/-1%,1/16W,G,SMD0402 | VISHAY ENTER TECHNO LOGY.INC | CRCW040249R9FKED |  | G |  |  |  |  |  |  |  |
|  |  |  |  |  | 148 | 610102700-024-G |  | RES,49.9 Ohm,+/-1%,1/16W,G,SMD0402 | PANASONIC INDUSTRIAL CO.,LTD. | ERJ2RKF49R9X |  | G |  |  |  |  |  |  |  |
|  |  |  |  | 149 | 149 | 610115J00-017-G | - | RES,33 Ohm,+/-1%,1/16W,G,SMD0402 | KOA SPEER ELECTRONICS, INC. | RK73H1ETTP33R0F | 2 | G | R446,R447 |  |  |  |  |  |  |
|  |  |  |  |  | 149 | 610115J00-012-G |  | RES,33 Ohm,+/-1%,1/16W,G,SMD0402 | WALSIN TECHNOLOGY CORPORATION | WR04X33R0FTL |  | G |  |  |  |  |  |  |  |
|  |  |  |  |  | 149 | 610115J00-011-G |  | RES,33 Ohm,+/-1%,1/16W,G,SMD0402 | YAGEO CORPORATION COMPONENT | RC0402FR-0733RL |  | G |  |  |  |  |  |  |  |
|  |  |  |  |  | 149 | 610115J00-044-G |  | RES,33 Ohm,+/-1%,1/16W,G,SMD0402 | TA-I TECHNOLOGY CO., LTD. | RM04FTN33R0 |  | G |  |  |  |  |  |  |  |
|  |  |  |  |  | 149 | 610115J00-024-G |  | RES,33 Ohm,+/-1%,1/16W,G,SMD0402 | PANASONIC INDUSTRIAL CO.,LTD. | ERJ2RKF33R0X |  | G |  |  |  |  |  |  |  |
|  |  |  |  | 150 | 150 | 61011T800-017-G | - | RES,240 Ohm,+/-1%,1/16W,G,SMD0402 | KOA SPEER ELECTRONICS, INC. | RK73H1ETTP2400F | 1 | G | R454 |  |  |  |  |  |  |
|  |  |  |  |  | 150 | 61011T800-012-G |  | RES,240 Ohm,+/-1%,1/16W,G,SMD0402 | WALSIN TECHNOLOGY CORPORATION | WR04X2400FTL |  | G |  |  |  |  |  |  |  |
|  |  |  |  |  | 150 | 61011T800-011-G |  | RES,240 Ohm,+/-1%,1/16W,G,SMD0402 | YAGEO CORPORATION COMPONENT | RC0402FR-07240RL |  | G |  |  |  |  |  |  |  |
|  |  |  |  |  | 150 | 61011T800-044-G |  | RES,240 Ohm,+/-1%,1/16W,G,SMD0402 | TA-I TECHNOLOGY CO., LTD. | RM04FTN2400 |  | G |  |  |  |  |  |  |  |
|  |  |  |  | 151 | 151 | 610112500-017-G | - | RES,475 Ohm,+/-1%,1/16W,G,SMD0402 | KOA SPEER ELECTRONICS, INC. | RK73H1ETTP4750F | 1 | G | R1411 |  |  |  |  |  |  |
|  |  |  |  |  | 151 | 610112500-012-G |  | RES,475 Ohm,+/-1%,1/16W,G,SMD0402 | WALSIN TECHNOLOGY CORPORATION | WR04X4750FTL |  | G |  |  |  |  |  |  |  |
|  |  |  |  |  | 151 | 610112500-011-G |  | RES,475 Ohm,+/-1%,1/16W,G,SMD0402 | YAGEO CORPORATION COMPONENT | RC0402FR-07475RL |  | G |  |  |  |  |  |  |  |
|  |  |  |  |  | 151 | 610112500-044-G |  | RES,475 Ohm,+/-1%,1/16W,G,SMD0402 | TA-I TECHNOLOGY CO., LTD. | RM04FTN4750 |  | G |  |  |  |  |  |  |  |
|  |  |  |  | 152 | 152 | 610107L00-017-G |  | RES,1 Ohm,+/-5%,1/10W,G,SMD0603 | KOA SPEER ELECTRONICS, INC. | RK73B1JTTD1R0J | 1 | G | R1413 |  |  |  |  |  |  |
|  |  |  |  |  | 152 | 610107L00-011-G |  | RES,1 Ohm,+/-5%,1/10W,G,SMD0603 | YAGEO CORPORATION COMPONENT | RC0603JR-071RL |  | G |  |  |  |  |  |  |  |
|  |  |  |  |  | 152 | 610107L00-012-G |  | RES,1 Ohm,+/-5%,1/10W,G,SMD0603 | WALSIN TECHNOLOGY CORPORATION | WR06X1R0JTL |  | G |  |  |  |  |  |  |  |
|  |  |  |  |  | 152 | 610107L00-044-G |  | RES,1 Ohm,+/-5%,1/10W,G,SMD0603 | TA-I TECHNOLOGY CO., LTD. | RM06JTN1R0 |  | G |  |  |  |  |  |  |  |
|  |  |  |  | 153 | 153 | 610107C00-017-G | K9577 | RES,10KOhm,+/-5%,1/16W,G,SMD0402 | KOA SPEER ELECTRONICS, INC. | RK73B1ETTP103J | 1 | G | R1426 |  |  |  |  |  |  |
|  |  |  |  |  | 153 | 610107C00-012-G |  | RES,10KOhm,+/-5%,1/16W,G,SMD0402 | WALSIN TECHNOLOGY CORPORATION | WR04X103JTL |  | G |  |  |  |  |  |  |  |
|  |  |  |  |  | 153 | 610107C00-011-G |  | RES,10KOhm,+/-5%,1/16W,G,SMD0402 | YAGEO CORPORATION COMPONENT | RC0402JR-0710KL |  | G |  |  |  |  |  |  |  |
|  |  |  |  |  | 153 | 610107C00-044-G |  | RES,10KOhm,+/-5%,1/16W,G,SMD0402 | TA-I TECHNOLOGY CO., LTD. | RM04JTN103 |  | G |  |  |  |  |  |  |  |
|  |  |  |  |  | 153 | 610107C00-024-G |  | RES,10KOhm,+/-5%,1/16W,G,SMD0402 | PANASONIC INDUSTRIAL CO.,LTD. | ERJ2GEJ103X |  | G |  |  |  |  |  |  |  |
|  |  |  |  |  | 153 | 610107C00-029-G |  | RES,10KOhm,+/-5%,1/16W,G,SMD0402 | VISHAY ENTER TECHNO LOGY.INC | CRCW040210K0JNED |  | G |  |  |  |  |  |  |  |
|  |  |  |  | 154 | 154 | 610118100-017-G | - | RES,1.4KOhm,+/-1%,1/16W,G,SMD0402 | KOA SPEER ELECTRONICS, INC. | RK73H1ETTP1401F | 4 | G | R1529,R1530,R1531,R1532 |  |  |  |  |  |  |
|  |  |  |  |  | 154 | 610118100-012-G |  | RES,1.4KOhm,+/-1%,1/16W,G,SMD0402 | WALSIN TECHNOLOGY CORPORATION | WR04X1401FTL |  | G |  |  |  |  |  |  |  |
|  |  |  |  |  | 154 | 610118100-011-G |  | RES,1.4KOhm,+/-1%,1/16W,G,SMD0402 | YAGEO CORPORATION COMPONENT | RC0402FR-071K4L |  | G |  |  |  |  |  |  |  |
|  |  |  |  |  | 154 | 610118100-044-G |  | RES,1.4KOhm,+/-1%,1/16W,G,SMD0402 | TA-I TECHNOLOGY CO., LTD | RM04FTN1401 |  | G |  |  |  |  |  |  |  |
|  |  |  |  |  | 154 | 610118100-024-G |  | RES,1.4KOhm,+/-1%,1/16W,G,SMD0402 | PANASONIC INDUSTRIAL CO.,LTD. | ERJ2RKF1401X |  | G |  |  |  |  |  |  |  |
|  |  |  |  | 155 | 155 | 21050LA00-217-G |  | IC,IDT,5V41234NLGI8,G,VFQFPN-16,SMD | INTEGRATED DEVICE TECHNOLOGY | 5V41234NLGI8 | 1 | G | U_CLKGEN |  |  |  |  |  |  |
|  |  |  |  | 156 | 156 | 41050UE00-233-G |  | Flash,MX29GL128FDT2I-11G,2.7~3.6V,128M,CFI,G,TSOP-56,SMD | MACRONIX INTERNATIONAL CO.,LTD. | MX29GL128FDT2I-11G | 1 | G | U_EXP_FLASH1 |  |  |  |  |  |  |
|  |  |  |  | 157 | 157 | 410405J00-214-G |  | EEPROM,M24C04-RMN6TP,1.8~5.5V,4K,2-Wire Serial,G,SO-8,SMD | STMICROELECTRONICS | M24C04-RMN6TP | 1 | G | U_EXP_FRU1 |  |  |  |  |  |  |
|  |  |  |  | 158 | 158 | 41040J500-232-G |  | EEPROM,24AA024T-I/SN,1.7V~5.5V,2K,I2C,G,SOIC-8,SMD | MICROCHIP TECHNOLOGY INC | 24AA024T-I/SN | 1 | G | U_EXP_FRU2 |  |  |  |  |  |  |
|  |  |  |  | 159 | 159 | 420103500-18R-G |  | SRAM,MR0D08BMA45R,3.3V,128K*8,G,FBGA-48,SMD | Everspin Technologies, Inc. | MR0D08BMA45R | 1 | G | U_EXP_NVSRAM1 |  |  |  |  |  |  |
|  |  |  |  | 160 | 160 | 311004V00-223-G |  | Logic IC,Translator,PCA9617ADMR2G,Vcca=0.8V~5.5V,Vccb=2.2V~5.5V,102ns,Micro8,8P,G | ON SEMICONDUCTOR CORP | PCA9617ADMR2G | 2 | G | U8,U_I2C_RE1 |  |  |  |  |  |  |
|  |  |  |  | 161 | 161 | 210826W00-283-G |  | IC,BROADCOM,PEX9797-AA80BCG,AA,G,FCBGA-1156,SMD | BROADCOM SINGAPORE PTE LTD. | SS14-0B00-00 | 1 | G | U_PEX_SW1 |  |  |  |  |  |  |
|  |  |  |  | 162 | 162 | 31010J400-131-G |  | IC,Gate&Inverter,TC7SZ08FU,1.8~5.5V,G,SSOP-5,SMD | TOSHIBA ELECTRONICS ASIA LTD | TC7SZ08FU | 2 | G | U2,U108 |  |  |  |  |  |  |
|  |  |  |  | 163 | 163 | 210828A00-GUW-G |  | IC,AVAGO,SX00-0B00-00,G,fpBGA-1197,SMD | AVAGO TECHNOLOGIES INTERNATION/AGILENT SEMICONDUCTOR | SX00-0B00-00 | 1 | G | U3 |  |  |  |  |  |  |
|  |  |  |  | 164 | 164 | 32020WJ00-183-G | - | IC,Power Controller,TPS3808G01DBVR,G,SOT23-6,SMD | TEXAS INSTRUMENTS | TPS3808G01DBVR | 1 | G | U4 |  |  |  |  |  |  |
|  |  |  |  | 165 | 165 | 32022FF00-173-G |  | IC,Power Controller,MAX6315US29D1+T,G,SOT-143-4,SMD | MAXIM INTEGRATED PRODUCTS, INC. | MAX6315US29D1+T | 1 | G | U6 |  |  |  |  |  |  |
|  |  |  |  | 166 | 166 | 410405T00-223-G |  | EEPROM,CAT25256VI-GT3,1.8~5.5V,256K,SPI,G,SOIC-8,SMD | ON SEMICONDUCTOR CORP | CAT25256VI-GT3 | 2 | G | U9,U117 |  |  |  |  |  |  |
|  |  |  |  | 167 | 167 | 310408900-217-G | - | IC,Switch,74CBTLV3257PGG8,2.3~3.6V,G,TSSOP-16,SMD | INTEGRATED DEVICE TECHNOLOGY | 74CBTLV3257PGG8 | 1 | G | U27 |  |  |  |  |  |  |
|  |  |  |  | 168 | 168 | 310502C00-223-G |  | IC,Buffer,NL17SZ07DFT2G,1.65~5.50V,G,SC-88A/SOT-353-5,SMD | ON SEMICONDUCTOR CORP | NL17SZ07DFT2G | 2 | G | U107,U110 |  |  |  |  |  |  |
|  |  |  |  | 169 | 169 | 31050BH00-131-G |  | IC,Buffer,TC7SZ17FU,1.65~5.5V,G,SSOP-5,SMD | TOSHIBA ELECTRONICS ASIA LTD | TC7SZ17FU | 1 | G | U109 |  |  |  |  |  |  |
|  |  |  |  | 170 | 170 | 710124Y00-100-G |  | XTAL,25MHz,+/-20ppm,20pF,G,SMD | TXC CORPORATION | 7M25020015 | 1 | G | X1 |  |  |  |  |  |  |
|  |  |  |  | 171 | 171 | 71020C900-252-G |  | OSC,150MHz,+/-50ppm,3.3V,50ohm,G,SMD | PERICOM SEMICONDUCTOR CORP | S2692-150.0000(T) | 1 | G | Y1 |  |  |  |  |  |  |
|  |  |  |  | 172 | 172 | 340718A00-245-G |  | CONN,SAS,V/T,0.6mm,30u,G,SMD-74 | AMPHENOL SHANGHAI CORP. | U10-B074-250T | 12 | G | J_PCIE_OUT1,J_PCIE_IN1,J_PCIE_OUT2,J_PCIE_IN2,J_PCIE_OUT3,J_PCIE_OUT4,J4,J_PCIE_OUT5,J5,J_PCIE_OUT6,J6,J_PCIE_OUT7 |  |  |  |  |  |  |
|  |  |  |  | 173 | 173 | 34066Q200-317-G |  | CONN,Header,Power,2X8,V/T,Bla,3mm,G,DIP-16 | MOLEX INCORPORATED | 43045-1627 | 1 | G | J_PWR_BP |  |  |  |  |  |  |
|  |  |  |  | 174 | 174 | 340636700-600-G |  | CONN,Header,Power,2X8,V/T,Whi,4.2mm,G,DIP-16 | FOXCONN TECHNOLOGY CO.,LTD. | HM3508E-HP1 | 1 | G | J_PWR_IN |  |  |  |  |  |  |
|  |  |  |  | 175 | 175 | 340716800-245-G |  | CONN,SAS,V/T,Bla,0.75mm,30u,G,SMD-72 | AMPHENOL SHANGHAI CORP. | G40H4232212HR | 1 | G | J_SAS_IN1 |  |  |  |  |  |  |
|  |  |  |  | 176 | 176 | 340626400-600-G |  | CONN,Header,Shrouded,1X4,V/T,1mm,Ivo,G,SMD-4 | FOXCONN TECHNOLOGY CO.,LTD. | HS6104E | 2 | G | J_UART1,J_SMART1 |  |  |  |  |  |  |
|  |  |  |  | 177 | 177 | 3406ALW00-317-G |  | CONN,Header,Shrouded,2X5,V/T,Bla,2mm,30u,G,SMD-10 | MOLEX INCORPORATED | 87832-5423 | 1 | G | J3 |  |  |  |  |  |  |
|  |  |  |  | 178 | 178 | 34045GE00-GRS-G |  | CONN,SPI FLASH SOCKET,Bla,1.27mm,15u,G,SMD-8 | LOTES CO LTD | ASPI0001-P002A | 1 | G | U10 |  |  |  |  |  |  |
